FILE_TYPE = MACRO_DRAWING;
SET COLOR_WIRE YELLOW;
SET COLOR_PROP MONO;
SET COLOR_DOT WHITE;
SET COLOR_ARC YELLOW;
SET COLOR_BODY GREEN;
SET COLOR_NOTE MONO;
SET PROP_DISPLAY VALUE;
SET PAGE_NUMBER P158;
FORCEADD RES..1
(-2650 1525);
FORCEPROP 1 LAST LOCATION R9F24
J 0
(-2700 1625);
DISPLAY 0.617021 (-2700 1625);
PAINT AQUA (-2700 1625);
FORCEPROP 1 LASTPIN (-2550 1525) $PN 2
J 0
(-2588 1537);
DISPLAY 0.617021 (-2588 1537);
PAINT ORANGE (-2588 1537);
FORCEPROP 1 LAST TOLERANCE 5%
J 0
(-2650 1425);
DISPLAY 0.617021 (-2650 1425);
PAINT SKYBLUE (-2650 1425);
FORCEPROP 1 LASTPIN (-2750 1525) $PN 1
J 0
(-2738 1537);
DISPLAY 0.617021 (-2738 1537);
PAINT ORANGE (-2738 1537);
FORCEPROP 1 LAST MATERIAL EMPTY
J 0
(-2650 1375);
DISPLAY 0.617021 (-2650 1375);
PAINT RED (-2650 1375);
FORCEPROP 1 LAST WATTAGE 1/16W
J 2
(-2675 1375);
DISPLAY 0.617021 (-2675 1375);
PAINT SKYBLUE (-2675 1375);
FORCEPROP 1 LAST VALUE 0.0
J 2
(-2675 1425);
DISPLAY 0.617021 (-2675 1425);
PAINT SKYBLUE (-2675 1425);
FORCEPROP 1 LAST PART_NUMBER G21497-005
J 0
(-2525 1450);
DISPLAY 0.617021 (-2525 1450);
PAINT BLUE (-2525 1450);
FORCEPROP 1 LAST PACK_TYPE 0402
J 0
(-2400 1375);
DISPLAY 0.617021 (-2400 1375);
PAINT SKYBLUE (-2400 1375);
FORCEPROP 2 LAST ROOM UART_MUX
J 0
(-2700 1675);
DISPLAY 1.021277 (-2700 1675);
PAINT ORANGE (-2700 1675);
DISPLAY INVISIBLE (-2700 1675);
FORCEPROP 1 LAST PATH I100
J 0
(-2700 1675);
DISPLAY 0.978723 (-2700 1675);
PAINT WHITE (-2700 1675);
DISPLAY INVISIBLE (-2700 1675);
FORCEPROP 2 LAST CDS_LOCATION R9F24
J 0
(-2700 1625);
DISPLAY 0.617021 (-2700 1625);
PAINT AQUA (-2700 1625);
DISPLAY INVISIBLE (-2700 1625);
FORCEPROP 2 LAST SEC 1
J 0
(-2700 1725);
DISPLAY 0.680851 (-2700 1725);
PAINT MONO (-2700 1725);
DISPLAY INVISIBLE (-2700 1725);
FORCEPROP 2 LAST SEC_TYPE 0402
J 0
(-2700 1725);
DISPLAY 1.021277 (-2700 1725);
PAINT ORANGE (-2700 1725);
DISPLAY INVISIBLE (-2700 1725);
FORCEPROP 2 LAST BOM_COST DEBUG
J 0
(-2700 1725);
DISPLAY 1.021277 (-2700 1725);
PAINT ORANGE (-2700 1725);
DISPLAY INVISIBLE (-2700 1725);
FORCEPROP 2 LAST CDS_LIB mstr_discrete
J 0
(-2650 1525);
PAINT ORANGE (-2650 1525);
DISPLAY INVISIBLE (-2650 1525);
FORCEADD OFFPAGE..1
(-3950 2675);
FORCEPROP 2 LAST $XR1 190 
J 0
(-4202 2639);
DISPLAY 0.638298 (-4202 2639);
PAINT MONO (-4202 2639);
FORCEPROP 2 LAST $XR0 145 
J 0
(-4202 2675);
DISPLAY 0.638298 (-4202 2675);
PAINT MONO (-4202 2675);
FORCEPROP 1 LAST COMMENT_BODY TRUE
J 0
(-3825 2575);
DISPLAY 0.872340 (-3825 2575);
PAINT GREEN (-3825 2575);
DISPLAY INVISIBLE (-3825 2575);
FORCEPROP 1 LAST OFFPAGE TRUE
J 0
(-3625 2550);
DISPLAY 0.872340 (-3625 2550);
PAINT GREEN (-3625 2550);
DISPLAY INVISIBLE (-3625 2550);
FORCEPROP 2 LAST CDS_LIB mstr_standard
J 0
(-3950 2675);
PAINT ORANGE (-3950 2675);
DISPLAY INVISIBLE (-3950 2675);
FORCEPROP 2 LAST PATH I124
J 0
(-4225 2725);
DISPLAY 1.021277 (-4225 2725);
PAINT ORANGE (-4225 2725);
DISPLAY INVISIBLE (-4225 2725);
FORCEADD OFFPAGE..1
(-3950 2575);
FORCEPROP 2 LAST $XR0 145 
J 0
(-4202 2575);
DISPLAY 0.638298 (-4202 2575);
PAINT MONO (-4202 2575);
FORCEPROP 1 LAST COMMENT_BODY TRUE
J 0
(-3825 2475);
DISPLAY 0.872340 (-3825 2475);
PAINT GREEN (-3825 2475);
DISPLAY INVISIBLE (-3825 2475);
FORCEPROP 1 LAST OFFPAGE TRUE
J 0
(-3625 2450);
DISPLAY 0.872340 (-3625 2450);
PAINT GREEN (-3625 2450);
DISPLAY INVISIBLE (-3625 2450);
FORCEPROP 2 LAST CDS_LIB mstr_standard
J 0
(-3950 2575);
PAINT ORANGE (-3950 2575);
DISPLAY INVISIBLE (-3950 2575);
FORCEPROP 2 LAST PATH I125
J 0
(-4225 2625);
DISPLAY 1.021277 (-4225 2625);
PAINT ORANGE (-4225 2625);
DISPLAY INVISIBLE (-4225 2625);
FORCEADD OFFPAGE..1
(-3950 2625);
FORCEPROP 2 LAST $XR2 190 
J 0
(-4292 2661);
DISPLAY 0.638298 (-4292 2661);
PAINT MONO (-4292 2661);
FORCEPROP 2 LAST $XR1 150 
J 0
(-4292 2589);
DISPLAY 0.638298 (-4292 2589);
PAINT MONO (-4292 2589);
FORCEPROP 2 LAST $XR0 145 
J 0
(-4292 2625);
DISPLAY 0.638298 (-4292 2625);
PAINT MONO (-4292 2625);
FORCEPROP 1 LAST COMMENT_BODY TRUE
J 0
(-3825 2525);
DISPLAY 0.872340 (-3825 2525);
PAINT GREEN (-3825 2525);
DISPLAY INVISIBLE (-3825 2525);
FORCEPROP 1 LAST OFFPAGE TRUE
J 0
(-3625 2500);
DISPLAY 0.872340 (-3625 2500);
PAINT GREEN (-3625 2500);
DISPLAY INVISIBLE (-3625 2500);
FORCEPROP 2 LAST CDS_LIB mstr_standard
J 0
(-3950 2625);
PAINT ORANGE (-3950 2625);
DISPLAY INVISIBLE (-3950 2625);
FORCEPROP 2 LAST PATH I126
J 0
(-4225 2675);
DISPLAY 1.021277 (-4225 2675);
PAINT ORANGE (-4225 2675);
DISPLAY INVISIBLE (-4225 2675);
FORCEADD OFFPAGE..2
(-400 850);
FORCEPROP 2 LAST CDS_LIB mstr_standard
J 0
(-400 850);
PAINT MONO (-400 850);
DISPLAY INVISIBLE (-400 850);
FORCEPROP 2 LAST PATH I127
J 0
(50 900);
DISPLAY 1.021277 (50 900);
PAINT ORANGE (50 900);
DISPLAY INVISIBLE (50 900);
FORCEPROP 1 LAST OFFPAGE TRUE
J 0
(-75 725);
DISPLAY 0.872340 (-75 725);
PAINT GREEN (-75 725);
DISPLAY INVISIBLE (-75 725);
FORCEPROP 1 LAST COMMENT_BODY TRUE
J 0
(-445 755);
DISPLAY 0.872340 (-445 755);
PAINT GREEN (-445 755);
DISPLAY INVISIBLE (-445 755);
FORCEPROP 2 LAST $XR0 145 
J 0
(-211 850);
DISPLAY 0.638298 (-211 850);
PAINT MONO (-211 850);
DISPLAY INVISIBLE (-211 850);
FORCEADD OFFPAGE..2
(-400 950);
FORCEPROP 2 LAST CDS_LIB mstr_standard
J 0
(-400 950);
PAINT MONO (-400 950);
DISPLAY INVISIBLE (-400 950);
FORCEPROP 2 LAST PATH I128
J 0
(50 1000);
DISPLAY 1.021277 (50 1000);
PAINT ORANGE (50 1000);
DISPLAY INVISIBLE (50 1000);
FORCEPROP 1 LAST OFFPAGE TRUE
J 0
(-75 825);
DISPLAY 0.872340 (-75 825);
PAINT GREEN (-75 825);
DISPLAY INVISIBLE (-75 825);
FORCEPROP 1 LAST COMMENT_BODY TRUE
J 0
(-445 855);
DISPLAY 0.872340 (-445 855);
PAINT GREEN (-445 855);
DISPLAY INVISIBLE (-445 855);
FORCEPROP 2 LAST $XR1 190 
J 0
(-211 950);
DISPLAY 0.638298 (-211 950);
PAINT MONO (-211 950);
DISPLAY INVISIBLE (-211 950);
FORCEPROP 2 LAST $XR0 145 
J 0
(-211 950);
DISPLAY 0.638298 (-211 950);
PAINT MONO (-211 950);
DISPLAY INVISIBLE (-211 950);
FORCEADD OFFPAGE..2
(-400 900);
FORCEPROP 2 LAST CDS_LIB mstr_standard
J 0
(-400 900);
PAINT MONO (-400 900);
DISPLAY INVISIBLE (-400 900);
FORCEPROP 2 LAST PATH I129
J 0
(50 950);
DISPLAY 1.021277 (50 950);
PAINT ORANGE (50 950);
DISPLAY INVISIBLE (50 950);
FORCEPROP 1 LAST OFFPAGE TRUE
J 0
(-75 775);
DISPLAY 0.872340 (-75 775);
PAINT GREEN (-75 775);
DISPLAY INVISIBLE (-75 775);
FORCEPROP 1 LAST COMMENT_BODY TRUE
J 0
(-445 805);
DISPLAY 0.872340 (-445 805);
PAINT GREEN (-445 805);
DISPLAY INVISIBLE (-445 805);
FORCEPROP 2 LAST $XR1 190 
J 0
(-211 900);
DISPLAY 0.638298 (-211 900);
PAINT MONO (-211 900);
DISPLAY INVISIBLE (-211 900);
FORCEPROP 2 LAST $XR0 145 
J 0
(-211 900);
DISPLAY 0.638298 (-211 900);
PAINT MONO (-211 900);
DISPLAY INVISIBLE (-211 900);
FORCEADD LED..3
(-5725 3200);
FORCEPROP 2 LASTPIN (-5625 3200) $PN 1
J 0
(-5615 3210);
DISPLAY 0.617021 (-5615 3210);
PAINT ORANGE (-5615 3210);
FORCEPROP 1 LAST LOCATION DS9A4
J 0
(-5825 3400);
DISPLAY 0.617021 (-5825 3400);
PAINT AQUA (-5825 3400);
FORCEPROP 1 LAST MATERIAL IC
J 0
(-5825 3350);
DISPLAY 0.617021 (-5825 3350);
PAINT SKYBLUE (-5825 3350);
FORCEPROP 2 LASTPIN (-5825 3200) $PN 2
J 2
(-5835 3210);
DISPLAY 0.617021 (-5835 3210);
PAINT ORANGE (-5835 3210);
FORCEPROP 1 LAST COLOR GREEN
J 0
(-5825 3300);
DISPLAY 0.617021 (-5825 3300);
PAINT BLUE (-5825 3300);
FORCEPROP 1 LAST PART_NUMBER D14725-022
J 0
(-5825 3050);
DISPLAY 0.617021 (-5825 3050);
PAINT BLUE (-5825 3050);
FORCEPROP 1 LAST PATH I130
J 0
(-5375 3350);
DISPLAY 0.978723 (-5375 3350);
PAINT BLUE (-5375 3350);
DISPLAY INVISIBLE (-5375 3350);
FORCEPROP 1 LAST PACK_TYPE A1LF
J 0
(-5825 3450);
DISPLAY 0.978723 (-5825 3450);
PAINT SKYBLUE (-5825 3450);
DISPLAY INVISIBLE (-5825 3450);
FORCEPROP 2 LAST ROOM UART_MUX
J 0
(-5825 3450);
DISPLAY 1.021277 (-5825 3450);
PAINT ORANGE (-5825 3450);
DISPLAY INVISIBLE (-5825 3450);
FORCEPROP 2 LAST CDS_LOCATION DS9A4
J 0
(-5825 3400);
DISPLAY 0.617021 (-5825 3400);
PAINT AQUA (-5825 3400);
DISPLAY INVISIBLE (-5825 3400);
FORCEPROP 2 LAST SEC 1
J 0
(-5825 3450);
DISPLAY 0.680851 (-5825 3450);
PAINT MONO (-5825 3450);
DISPLAY INVISIBLE (-5825 3450);
FORCEPROP 2 LAST SEC_TYPE A1LF
J 0
(-5825 3450);
DISPLAY 1.021277 (-5825 3450);
PAINT ORANGE (-5825 3450);
DISPLAY INVISIBLE (-5825 3450);
FORCEPROP 2 LAST BOM_COST DEBUG
J 0
(-5825 3500);
DISPLAY 1.021277 (-5825 3500);
PAINT ORANGE (-5825 3500);
DISPLAY INVISIBLE (-5825 3500);
FORCEPROP 2 LAST CDS_LIB mstr_discrete
J 0
(-5725 3200);
PAINT ORANGE (-5725 3200);
DISPLAY INVISIBLE (-5725 3200);
FORCEADD RES..1
(-4875 3200);
FORCEPROP 1 LAST PART_NUMBER G21497-028
J 0
(-4925 3300);
DISPLAY 0.617021 (-4925 3300);
PAINT BLUE (-4925 3300);
FORCEPROP 1 LAST LOCATION R1L43
J 0
(-4925 3250);
DISPLAY 0.617021 (-4925 3250);
PAINT AQUA (-4925 3250);
FORCEPROP 1 LASTPIN (-4775 3200) $PN 2
J 0
(-4813 3212);
DISPLAY 0.617021 (-4813 3212);
PAINT ORANGE (-4813 3212);
FORCEPROP 1 LAST TOLERANCE 5%
J 0
(-4875 3100);
DISPLAY 0.617021 (-4875 3100);
PAINT SKYBLUE (-4875 3100);
FORCEPROP 1 LAST WATTAGE 1/16W
J 2
(-4900 3050);
DISPLAY 0.617021 (-4900 3050);
PAINT SKYBLUE (-4900 3050);
FORCEPROP 1 LAST VALUE 330
J 2
(-4900 3100);
DISPLAY 0.617021 (-4900 3100);
PAINT SKYBLUE (-4900 3100);
FORCEPROP 1 LASTPIN (-4975 3200) $PN 1
J 0
(-4963 3212);
DISPLAY 0.617021 (-4963 3212);
PAINT ORANGE (-4963 3212);
FORCEPROP 1 LAST MATERIAL CHIP
J 0
(-4875 3050);
DISPLAY 0.617021 (-4875 3050);
PAINT SKYBLUE (-4875 3050);
FORCEPROP 1 LAST PACK_TYPE 0402
J 0
(-4625 3050);
DISPLAY 0.617021 (-4625 3050);
PAINT SKYBLUE (-4625 3050);
FORCEPROP 2 LAST ROOM UART_MUX
J 0
(-4925 3350);
DISPLAY 1.021277 (-4925 3350);
PAINT ORANGE (-4925 3350);
DISPLAY INVISIBLE (-4925 3350);
FORCEPROP 2 LAST SEC_TYPE 0402
J 0
(-4925 3400);
DISPLAY 1.021277 (-4925 3400);
PAINT ORANGE (-4925 3400);
DISPLAY INVISIBLE (-4925 3400);
FORCEPROP 2 LAST BOM_COST DEBUG
J 0
(-4925 3400);
DISPLAY 1.021277 (-4925 3400);
PAINT ORANGE (-4925 3400);
DISPLAY INVISIBLE (-4925 3400);
FORCEPROP 2 LAST SEC 1
J 0
(-4925 3400);
DISPLAY 0.680851 (-4925 3400);
PAINT MONO (-4925 3400);
DISPLAY INVISIBLE (-4925 3400);
FORCEPROP 1 LAST PATH I131
J 0
(-4925 3350);
DISPLAY 0.978723 (-4925 3350);
PAINT WHITE (-4925 3350);
DISPLAY INVISIBLE (-4925 3350);
FORCEPROP 2 LAST CDS_LOCATION R1L43
J 0
(-4925 3250);
DISPLAY 0.617021 (-4925 3250);
PAINT AQUA (-4925 3250);
DISPLAY INVISIBLE (-4925 3250);
FORCEPROP 2 LAST CDS_LIB mstr_discrete
J 0
(-4875 3200);
PAINT ORANGE (-4875 3200);
DISPLAY INVISIBLE (-4875 3200);
FORCEADD OFFPAGE..1
(-7100 3200);
FORCEPROP 2 LAST $XR3 158 
J 0
(-7712 3200);
DISPLAY 0.638298 (-7712 3200);
PAINT MONO (-7712 3200);
FORCEPROP 2 LAST $XR2 144 
J 0
(-7592 3200);
DISPLAY 0.638298 (-7592 3200);
PAINT MONO (-7592 3200);
FORCEPROP 2 LAST $XR1 120 
J 0
(-7472 3200);
DISPLAY 0.638298 (-7472 3200);
PAINT MONO (-7472 3200);
FORCEPROP 2 LAST $XR0 190 
J 0
(-7352 3200);
DISPLAY 0.638298 (-7352 3200);
PAINT MONO (-7352 3200);
FORCEPROP 1 LAST COMMENT_BODY TRUE
J 0
(-6975 3100);
DISPLAY 0.872340 (-6975 3100);
PAINT GREEN (-6975 3100);
DISPLAY INVISIBLE (-6975 3100);
FORCEPROP 1 LAST OFFPAGE TRUE
J 0
(-6775 3075);
DISPLAY 0.872340 (-6775 3075);
PAINT GREEN (-6775 3075);
DISPLAY INVISIBLE (-6775 3075);
FORCEPROP 2 LAST PATH I132
J 0
(-7050 3275);
DISPLAY 1.021277 (-7050 3275);
PAINT ORANGE (-7050 3275);
DISPLAY INVISIBLE (-7050 3275);
FORCEPROP 2 LAST CDS_LIB mstr_standard
J 0
(-7100 3200);
PAINT ORANGE (-7100 3200);
DISPLAY INVISIBLE (-7100 3200);
FORCEADD LED..3
(-5725 3600);
FORCEPROP 2 LASTPIN (-5625 3600) $PN 1
J 0
(-5615 3610);
DISPLAY 0.617021 (-5615 3610);
PAINT ORANGE (-5615 3610);
FORCEPROP 1 LAST PART_NUMBER D14725-022
J 0
(-5825 3450);
DISPLAY 0.617021 (-5825 3450);
PAINT BLUE (-5825 3450);
FORCEPROP 1 LAST LOCATION DS9A7
J 0
(-5825 3800);
DISPLAY 0.617021 (-5825 3800);
PAINT AQUA (-5825 3800);
FORCEPROP 1 LAST MATERIAL IC
J 0
(-5825 3750);
DISPLAY 0.617021 (-5825 3750);
PAINT SKYBLUE (-5825 3750);
FORCEPROP 2 LASTPIN (-5825 3600) $PN 2
J 2
(-5835 3610);
DISPLAY 0.617021 (-5835 3610);
PAINT ORANGE (-5835 3610);
FORCEPROP 1 LAST COLOR GREEN
J 0
(-5825 3700);
DISPLAY 0.617021 (-5825 3700);
PAINT BLUE (-5825 3700);
FORCEPROP 1 LAST PATH I134
J 0
(-5375 3750);
DISPLAY 0.978723 (-5375 3750);
PAINT BLUE (-5375 3750);
DISPLAY INVISIBLE (-5375 3750);
FORCEPROP 1 LAST PACK_TYPE A1LF
J 0
(-5825 3850);
DISPLAY 0.978723 (-5825 3850);
PAINT SKYBLUE (-5825 3850);
DISPLAY INVISIBLE (-5825 3850);
FORCEPROP 2 LAST ROOM UART_MUX
J 0
(-5825 3850);
DISPLAY 1.021277 (-5825 3850);
PAINT ORANGE (-5825 3850);
DISPLAY INVISIBLE (-5825 3850);
FORCEPROP 2 LAST SEC 1
J 0
(-5825 3850);
DISPLAY 0.680851 (-5825 3850);
PAINT MONO (-5825 3850);
DISPLAY INVISIBLE (-5825 3850);
FORCEPROP 2 LAST SEC_TYPE A1LF
J 0
(-5825 3850);
DISPLAY 1.021277 (-5825 3850);
PAINT ORANGE (-5825 3850);
DISPLAY INVISIBLE (-5825 3850);
FORCEPROP 2 LAST BOM_COST DEBUG
J 0
(-5825 3900);
DISPLAY 1.021277 (-5825 3900);
PAINT ORANGE (-5825 3900);
DISPLAY INVISIBLE (-5825 3900);
FORCEPROP 2 LAST CDS_LOCATION DS9A7
J 0
(-5825 3800);
DISPLAY 0.617021 (-5825 3800);
PAINT AQUA (-5825 3800);
DISPLAY INVISIBLE (-5825 3800);
FORCEPROP 2 LAST CDS_LIB mstr_discrete
J 0
(-5725 3600);
PAINT ORANGE (-5725 3600);
DISPLAY INVISIBLE (-5725 3600);
FORCEADD P3V3_STBY..1
(-4400 3850);
FORCEPROP 3 LASTPIN (-4400 3800) SIG_NAME P3V3_STBY\g
J 0
(-4390 3810);
DISPLAY 0.659574 (-4390 3810);
PAINT MONO (-4390 3810);
DISPLAY INVISIBLE (-4390 3810);
FORCEPROP 1 LAST HDL_POWER P3V3_STBY
J 0
(-4700 3725);
DISPLAY 0.872340 (-4700 3725);
PAINT ORANGE (-4700 3725);
DISPLAY INVISIBLE (-4700 3725);
FORCEPROP 1 LAST BODY_TYPE PLUMBING
J 0
(-4445 3807);
DISPLAY 0.340426 (-4445 3807);
PAINT GREEN (-4445 3807);
DISPLAY INVISIBLE (-4445 3807);
FORCEPROP 1 LAST SIZE 1B
J 0
(-4355 3872);
DISPLAY 0.340426 (-4355 3872);
PAINT GREEN (-4355 3872);
DISPLAY INVISIBLE (-4355 3872);
FORCEPROP 2 LAST CDS_LIB mstr_symbols
J 0
(-4400 3850);
PAINT ORANGE (-4400 3850);
DISPLAY INVISIBLE (-4400 3850);
FORCEPROP 1 LAST PATH I135
J 0
(-4355 3852);
DISPLAY 0.340426 (-4355 3852);
PAINT GREEN (-4355 3852);
DISPLAY INVISIBLE (-4355 3852);
FORCEPROP 1 LAST VOLTAGE 3.3V
J 0
(-4445 3807);
DISPLAY 0.340426 (-4445 3807);
PAINT SKYBLUE (-4445 3807);
DISPLAY INVISIBLE (-4445 3807);
FORCEADD RES..1
(-4875 3600);
FORCEPROP 1 LAST PART_NUMBER G21497-028
J 0
(-4925 3700);
DISPLAY 0.617021 (-4925 3700);
PAINT BLUE (-4925 3700);
FORCEPROP 1 LAST WATTAGE 1/16W
J 2
(-4900 3450);
DISPLAY 0.617021 (-4900 3450);
PAINT SKYBLUE (-4900 3450);
FORCEPROP 1 LAST VALUE 330
J 2
(-4900 3500);
DISPLAY 0.617021 (-4900 3500);
PAINT SKYBLUE (-4900 3500);
FORCEPROP 1 LAST MATERIAL CHIP
J 0
(-4875 3450);
DISPLAY 0.617021 (-4875 3450);
PAINT SKYBLUE (-4875 3450);
FORCEPROP 1 LASTPIN (-4975 3600) $PN 1
J 0
(-4963 3612);
DISPLAY 0.617021 (-4963 3612);
PAINT ORANGE (-4963 3612);
FORCEPROP 1 LAST LOCATION R1L44
J 0
(-4925 3650);
DISPLAY 0.617021 (-4925 3650);
PAINT AQUA (-4925 3650);
FORCEPROP 1 LASTPIN (-4775 3600) $PN 2
J 0
(-4813 3612);
DISPLAY 0.617021 (-4813 3612);
PAINT ORANGE (-4813 3612);
FORCEPROP 1 LAST PACK_TYPE 0402
J 0
(-4625 3450);
DISPLAY 0.617021 (-4625 3450);
PAINT SKYBLUE (-4625 3450);
FORCEPROP 1 LAST TOLERANCE 5%
J 0
(-4875 3500);
DISPLAY 0.617021 (-4875 3500);
PAINT SKYBLUE (-4875 3500);
FORCEPROP 2 LAST SEC 1
J 0
(-4925 3800);
DISPLAY 0.680851 (-4925 3800);
PAINT MONO (-4925 3800);
DISPLAY INVISIBLE (-4925 3800);
FORCEPROP 2 LAST CDS_LIB mstr_discrete
J 0
(-4875 3600);
PAINT ORANGE (-4875 3600);
DISPLAY INVISIBLE (-4875 3600);
FORCEPROP 2 LAST SEC_TYPE 0402
J 0
(-4925 3800);
DISPLAY 1.021277 (-4925 3800);
PAINT ORANGE (-4925 3800);
DISPLAY INVISIBLE (-4925 3800);
FORCEPROP 2 LAST CDS_LOCATION R1L44
J 0
(-4925 3650);
DISPLAY 0.617021 (-4925 3650);
PAINT AQUA (-4925 3650);
DISPLAY INVISIBLE (-4925 3650);
FORCEPROP 2 LAST BOM_COST DEBUG
J 0
(-4925 3800);
DISPLAY 1.021277 (-4925 3800);
PAINT ORANGE (-4925 3800);
DISPLAY INVISIBLE (-4925 3800);
FORCEPROP 2 LAST ROOM UART_MUX
J 0
(-4925 3750);
DISPLAY 1.021277 (-4925 3750);
PAINT ORANGE (-4925 3750);
DISPLAY INVISIBLE (-4925 3750);
FORCEPROP 1 LAST PATH I136
J 0
(-4925 3750);
DISPLAY 0.978723 (-4925 3750);
PAINT WHITE (-4925 3750);
DISPLAY INVISIBLE (-4925 3750);
FORCEADD OFFPAGE..1
(-7100 3600);
FORCEPROP 2 LAST $XR3 158 
J 0
(-7712 3600);
DISPLAY 0.638298 (-7712 3600);
PAINT MONO (-7712 3600);
FORCEPROP 2 LAST $XR2 144 
J 0
(-7592 3600);
DISPLAY 0.638298 (-7592 3600);
PAINT MONO (-7592 3600);
FORCEPROP 2 LAST $XR1 120 
J 0
(-7472 3600);
DISPLAY 0.638298 (-7472 3600);
PAINT MONO (-7472 3600);
FORCEPROP 2 LAST $XR0 190 
J 0
(-7352 3600);
DISPLAY 0.638298 (-7352 3600);
PAINT MONO (-7352 3600);
FORCEPROP 1 LAST COMMENT_BODY TRUE
J 0
(-6975 3500);
DISPLAY 0.872340 (-6975 3500);
PAINT GREEN (-6975 3500);
DISPLAY INVISIBLE (-6975 3500);
FORCEPROP 1 LAST OFFPAGE TRUE
J 0
(-6775 3475);
DISPLAY 0.872340 (-6775 3475);
PAINT GREEN (-6775 3475);
DISPLAY INVISIBLE (-6775 3475);
FORCEPROP 2 LAST CDS_LIB mstr_standard
J 0
(-7100 3600);
PAINT ORANGE (-7100 3600);
DISPLAY INVISIBLE (-7100 3600);
FORCEPROP 2 LAST PATH I137
J 0
(-7050 3675);
DISPLAY 1.021277 (-7050 3675);
PAINT ORANGE (-7050 3675);
DISPLAY INVISIBLE (-7050 3675);
FORCEADD OFFPAGE..1
(-3925 3750);
FORCEPROP 2 LAST $XR0 181 
J 0
(-4177 3750);
DISPLAY 0.638298 (-4177 3750);
PAINT MONO (-4177 3750);
FORCEPROP 1 LAST COMMENT_BODY TRUE
J 0
(-3800 3650);
DISPLAY 0.872340 (-3800 3650);
PAINT GREEN (-3800 3650);
DISPLAY INVISIBLE (-3800 3650);
FORCEPROP 1 LAST OFFPAGE TRUE
J 0
(-3600 3625);
DISPLAY 0.872340 (-3600 3625);
PAINT GREEN (-3600 3625);
DISPLAY INVISIBLE (-3600 3625);
FORCEPROP 2 LAST PATH I144
J 0
(-3750 3825);
DISPLAY 1.021277 (-3750 3825);
PAINT ORANGE (-3750 3825);
DISPLAY INVISIBLE (-3750 3825);
FORCEPROP 2 LAST CDS_LIB mstr_standard
J 0
(-3925 3750);
PAINT ORANGE (-3925 3750);
DISPLAY INVISIBLE (-3925 3750);
FORCEADD OFFPAGE..2
(-475 1775);
FORCEPROP 2 LAST $XR0 181 
J 0
(-286 1775);
DISPLAY 0.638298 (-286 1775);
PAINT MONO (-286 1775);
FORCEPROP 1 LAST COMMENT_BODY TRUE
J 0
(-520 1680);
DISPLAY 0.872340 (-520 1680);
PAINT GREEN (-520 1680);
DISPLAY INVISIBLE (-520 1680);
FORCEPROP 1 LAST OFFPAGE TRUE
J 0
(-150 1650);
DISPLAY 0.872340 (-150 1650);
PAINT GREEN (-150 1650);
DISPLAY INVISIBLE (-150 1650);
FORCEPROP 2 LAST PATH I147
J 0
(-300 1850);
DISPLAY 1.021277 (-300 1850);
PAINT ORANGE (-300 1850);
DISPLAY INVISIBLE (-300 1850);
FORCEPROP 2 LAST CDS_LIB mstr_standard
J 0
(-475 1775);
PAINT ORANGE (-475 1775);
DISPLAY INVISIBLE (-475 1775);
FORCEADD RES..1
(-3125 3750);
FORCEPROP 1 LASTPIN (-3225 3750) $PN 1
J 0
(-3213 3762);
DISPLAY 0.787234 (-3213 3762);
PAINT ORANGE (-3213 3762);
FORCEPROP 1 LASTPIN (-3025 3750) $PN 2
J 0
(-3063 3762);
DISPLAY 0.787234 (-3063 3762);
PAINT ORANGE (-3063 3762);
FORCEPROP 1 LAST PACK_TYPE 0402
J 0
(-2875 3700);
DISPLAY 0.617021 (-2875 3700);
PAINT SKYBLUE (-2875 3700);
FORCEPROP 1 LAST VALUE 0.0
J 2
(-3150 3700);
DISPLAY 0.617021 (-3150 3700);
PAINT SKYBLUE (-3150 3700);
FORCEPROP 1 LAST PART_NUMBER G21497-005
J 0
(-3275 3625);
DISPLAY 0.617021 (-3275 3625);
PAINT BLUE (-3275 3625);
FORCEPROP 1 LAST TOLERANCE 5%
J 0
(-3050 3700);
DISPLAY 0.617021 (-3050 3700);
PAINT SKYBLUE (-3050 3700);
FORCEPROP 1 LAST MATERIAL CHIP
J 0
(-2975 3700);
DISPLAY 0.617021 (-2975 3700);
PAINT SKYBLUE (-2975 3700);
FORCEPROP 1 LAST LOCATION R9F65
J 0
(-3175 3800);
DISPLAY 0.617021 (-3175 3800);
PAINT AQUA (-3175 3800);
FORCEPROP 1 LAST WATTAGE 1/16W
J 2
(-3225 3700);
DISPLAY 0.617021 (-3225 3700);
PAINT SKYBLUE (-3225 3700);
FORCEPROP 2 LAST SEC_TYPE 0402
J 0
(-3175 3950);
DISPLAY 1.021277 (-3175 3950);
PAINT ORANGE (-3175 3950);
DISPLAY INVISIBLE (-3175 3950);
FORCEPROP 0 LAST SEC 1
J 0
(-3175 3850);
DISPLAY 0.680851 (-3175 3850);
PAINT MONO (-3175 3850);
DISPLAY INVISIBLE (-3175 3850);
FORCEPROP 2 LAST ROOM UART_MUX
J 0
(-3125 3850);
DISPLAY 1.021277 (-3125 3850);
PAINT ORANGE (-3125 3850);
DISPLAY INVISIBLE (-3125 3850);
FORCEPROP 2 LAST BOM_COST DEBUG
J 0
(-3125 3900);
DISPLAY 1.021277 (-3125 3900);
PAINT ORANGE (-3125 3900);
DISPLAY INVISIBLE (-3125 3900);
FORCEPROP 1 LAST PATH I148
J 0
(-3175 3900);
DISPLAY 0.978723 (-3175 3900);
PAINT WHITE (-3175 3900);
DISPLAY INVISIBLE (-3175 3900);
FORCEPROP 2 LAST CDS_LIB mstr_discrete
J 0
(-3125 3750);
PAINT MONO (-3125 3750);
DISPLAY INVISIBLE (-3125 3750);
FORCEADD RES..1
(-1250 850);
FORCEPROP 1 LAST LOCATION R9F68
J 0
(-1325 950);
DISPLAY 0.617021 (-1325 950);
PAINT AQUA (-1325 950);
FORCEPROP 1 LASTPIN (-1150 850) $PN 2
J 0
(-1188 862);
DISPLAY 0.787234 (-1188 862);
PAINT ORANGE (-1188 862);
FORCEPROP 1 LAST PACK_TYPE 0402
J 0
(-950 800);
DISPLAY 0.617021 (-950 800);
PAINT SKYBLUE (-950 800);
FORCEPROP 1 LAST VALUE 0.0
J 2
(-1275 800);
DISPLAY 0.617021 (-1275 800);
PAINT SKYBLUE (-1275 800);
FORCEPROP 1 LAST PART_NUMBER G21497-005
J 0
(-1400 675);
DISPLAY 0.617021 (-1400 675);
PAINT BLUE (-1400 675);
FORCEPROP 1 LAST WATTAGE 1/16W
J 2
(-1375 800);
DISPLAY 0.617021 (-1375 800);
PAINT SKYBLUE (-1375 800);
FORCEPROP 1 LAST TOLERANCE 5%
J 0
(-825 800);
DISPLAY 0.617021 (-825 800);
PAINT SKYBLUE (-825 800);
FORCEPROP 1 LAST MATERIAL EMPTY
J 0
(-1100 800);
DISPLAY 0.617021 (-1100 800);
PAINT RED (-1100 800);
FORCEPROP 1 LASTPIN (-1350 850) $PN 1
J 0
(-1338 862);
DISPLAY 0.787234 (-1338 862);
PAINT ORANGE (-1338 862);
FORCEPROP 2 LAST SEC_TYPE 0402
J 0
(-1300 1050);
DISPLAY 1.021277 (-1300 1050);
PAINT ORANGE (-1300 1050);
DISPLAY INVISIBLE (-1300 1050);
FORCEPROP 0 LAST SEC 1
J 0
(-1325 1000);
PAINT MONO (-1325 1000);
DISPLAY INVISIBLE (-1325 1000);
FORCEPROP 0 LAST CDS_LOCATION R9F68
J 0
(-1325 1000);
PAINT MONO (-1325 1000);
DISPLAY INVISIBLE (-1325 1000);
FORCEPROP 1 LAST PATH I149
J 0
(-1300 1000);
DISPLAY 0.978723 (-1300 1000);
PAINT WHITE (-1300 1000);
DISPLAY INVISIBLE (-1300 1000);
FORCEPROP 2 LAST CDS_LIB mstr_discrete
J 0
(-1250 850);
PAINT ORANGE (-1250 850);
DISPLAY INVISIBLE (-1250 850);
FORCEPROP 2 LAST BOM_COST DEBUG
J 0
(-1250 1000);
DISPLAY 1.021277 (-1250 1000);
PAINT ORANGE (-1250 1000);
DISPLAY INVISIBLE (-1250 1000);
FORCEPROP 2 LAST ROOM UART_MUX
J 0
(-1250 950);
DISPLAY 1.021277 (-1250 950);
PAINT ORANGE (-1250 950);
DISPLAY INVISIBLE (-1250 950);
FORCEADD RES..1
(-1100 1775);
FORCEPROP 1 LAST PART_NUMBER G21497-005
J 0
(-1250 1650);
DISPLAY 0.617021 (-1250 1650);
PAINT BLUE (-1250 1650);
FORCEPROP 1 LAST VALUE 0.0
J 2
(-1125 1725);
DISPLAY 0.617021 (-1125 1725);
PAINT SKYBLUE (-1125 1725);
FORCEPROP 1 LAST MATERIAL CHIP
J 0
(-950 1725);
DISPLAY 0.617021 (-950 1725);
PAINT SKYBLUE (-950 1725);
FORCEPROP 1 LAST TOLERANCE 5%
J 0
(-1025 1725);
DISPLAY 0.617021 (-1025 1725);
PAINT SKYBLUE (-1025 1725);
FORCEPROP 1 LASTPIN (-1000 1775) $PN 2
J 0
(-1038 1787);
DISPLAY 0.617021 (-1038 1787);
PAINT ORANGE (-1038 1787);
FORCEPROP 1 LASTPIN (-1200 1775) $PN 1
J 0
(-1188 1787);
DISPLAY 0.617021 (-1188 1787);
PAINT ORANGE (-1188 1787);
FORCEPROP 1 LAST LOCATION R9F69
J 0
(-1150 1825);
DISPLAY 0.617021 (-1150 1825);
PAINT AQUA (-1150 1825);
FORCEPROP 1 LAST PACK_TYPE 0402
J 0
(-850 1725);
DISPLAY 0.617021 (-850 1725);
PAINT SKYBLUE (-850 1725);
FORCEPROP 1 LAST WATTAGE 1/16W
J 2
(-1200 1725);
DISPLAY 0.617021 (-1200 1725);
PAINT SKYBLUE (-1200 1725);
FORCEPROP 0 LAST CDS_LOCATION R9F69
J 0
(-1150 1875);
PAINT MONO (-1150 1875);
DISPLAY INVISIBLE (-1150 1875);
FORCEPROP 1 LAST PATH I150
J 0
(-1150 1925);
DISPLAY 0.978723 (-1150 1925);
PAINT WHITE (-1150 1925);
DISPLAY INVISIBLE (-1150 1925);
FORCEPROP 2 LAST SEC 1
J 0
(-1150 1975);
DISPLAY 0.680851 (-1150 1975);
PAINT MONO (-1150 1975);
DISPLAY INVISIBLE (-1150 1975);
FORCEPROP 2 LAST SEC_TYPE 0402
J 0
(-1150 1975);
DISPLAY 1.021277 (-1150 1975);
PAINT ORANGE (-1150 1975);
DISPLAY INVISIBLE (-1150 1975);
FORCEPROP 2 LAST BOM_COST DEBUG
J 0
(-1100 1925);
DISPLAY 1.021277 (-1100 1925);
PAINT ORANGE (-1100 1925);
DISPLAY INVISIBLE (-1100 1925);
FORCEPROP 2 LAST ROOM UART_MUX
J 0
(-1100 1875);
DISPLAY 1.021277 (-1100 1875);
PAINT ORANGE (-1100 1875);
DISPLAY INVISIBLE (-1100 1875);
FORCEPROP 2 LAST CDS_LIB mstr_discrete
J 0
(-1100 1775);
PAINT ORANGE (-1100 1775);
DISPLAY INVISIBLE (-1100 1775);
FORCEPROP 0 LAST CDS_SEC 1
J 0
(-1150 1875);
PAINT MONO (-1150 1875);
DISPLAY INVISIBLE (-1150 1875);
FORCEADD RES..1
(-3150 2575);
FORCEPROP 1 LAST TOLERANCE 5%
J 0
(-3150 2475);
DISPLAY 0.617021 (-3150 2475);
PAINT SKYBLUE (-3150 2475);
FORCEPROP 1 LAST WATTAGE 1/16W
J 2
(-3175 2425);
DISPLAY 0.617021 (-3175 2425);
PAINT SKYBLUE (-3175 2425);
FORCEPROP 1 LAST PART_NUMBER G21497-005
J 0
(-3250 2375);
DISPLAY 0.617021 (-3250 2375);
PAINT BLUE (-3250 2375);
FORCEPROP 1 LAST PACK_TYPE 0402
J 0
(-2900 2425);
DISPLAY 0.617021 (-2900 2425);
PAINT SKYBLUE (-2900 2425);
FORCEPROP 1 LAST MATERIAL EMPTY
J 0
(-3150 2425);
DISPLAY 0.617021 (-3150 2425);
PAINT RED (-3150 2425);
FORCEPROP 1 LAST LOCATION R9F66
J 0
(-3200 2625);
DISPLAY 0.617021 (-3200 2625);
PAINT AQUA (-3200 2625);
FORCEPROP 1 LAST VALUE 0.0
J 2
(-3175 2475);
DISPLAY 0.617021 (-3175 2475);
PAINT SKYBLUE (-3175 2475);
FORCEPROP 1 LASTPIN (-3050 2575) $PN 2
J 0
(-3088 2587);
DISPLAY 0.787234 (-3088 2587);
PAINT ORANGE (-3088 2587);
DISPLAY INVISIBLE (-3088 2587);
FORCEPROP 1 LASTPIN (-3250 2575) $PN 1
J 0
(-3238 2587);
DISPLAY 0.787234 (-3238 2587);
PAINT ORANGE (-3238 2587);
DISPLAY INVISIBLE (-3238 2587);
FORCEPROP 2 LAST CDS_LIB mstr_discrete
J 0
(-3150 2575);
PAINT MONO (-3150 2575);
DISPLAY INVISIBLE (-3150 2575);
FORCEPROP 1 LAST PATH I152
J 0
(-3200 2725);
DISPLAY 0.978723 (-3200 2725);
PAINT WHITE (-3200 2725);
DISPLAY INVISIBLE (-3200 2725);
FORCEPROP 2 LAST BOM_COST DEBUG
J 0
(-3200 2725);
DISPLAY 1.021277 (-3200 2725);
PAINT ORANGE (-3200 2725);
DISPLAY INVISIBLE (-3200 2725);
FORCEPROP 2 LAST ROOM UART_MUX
J 0
(-3200 2675);
DISPLAY 1.021277 (-3200 2675);
PAINT ORANGE (-3200 2675);
DISPLAY INVISIBLE (-3200 2675);
FORCEADD RES..2
(-2300 1200);
FORCEPROP 1 LAST PACK_TYPE 0402
J 0
(-2260 1025);
DISPLAY 0.617021 (-2260 1025);
PAINT SKYBLUE (-2260 1025);
FORCEPROP 1 LAST MATERIAL CHIP
J 0
(-2260 1125);
DISPLAY 0.617021 (-2260 1125);
PAINT SKYBLUE (-2260 1125);
FORCEPROP 1 LASTPIN (-2300 1100) $PN 2
J 0
(-2295 1110);
DISPLAY 0.617021 (-2295 1110);
PAINT ORANGE (-2295 1110);
FORCEPROP 1 LASTPIN (-2300 1300) $PN 1
J 0
(-2295 1262);
DISPLAY 0.617021 (-2295 1262);
PAINT ORANGE (-2295 1262);
FORCEPROP 0 LAST POP NOPOP
J 0
(-2250 975);
DISPLAY 0.638298 (-2250 975);
PAINT RED (-2250 975);
FORCEPROP 1 LAST LOCATION R9W33
J 0
(-2255 1325);
DISPLAY 0.617021 (-2255 1325);
PAINT AQUA (-2255 1325);
FORCEPROP 1 LAST VALUE 4.75K
J 0
(-2255 1275);
DISPLAY 0.617021 (-2255 1275);
PAINT SKYBLUE (-2255 1275);
FORCEPROP 1 LAST TOLERANCE 1%
J 0
(-2255 1225);
DISPLAY 0.617021 (-2255 1225);
PAINT SKYBLUE (-2255 1225);
FORCEPROP 1 LAST WATTAGE 1/16W
J 0
(-2260 1175);
DISPLAY 0.617021 (-2260 1175);
PAINT SKYBLUE (-2260 1175);
FORCEPROP 1 LAST PART_NUMBER G21796-072
J 0
(-2260 1075);
DISPLAY 0.617021 (-2260 1075);
PAINT BLUE (-2260 1075);
FORCEPROP 2 LAST ROOM BMC_MISC
J 0
(-2350 1300);
DISPLAY 1.021277 (-2350 1300);
PAINT ORANGE (-2350 1300);
DISPLAY INVISIBLE (-2350 1300);
FORCEPROP 2 LAST CDS_LIB mstr_discrete
J 0
(-2300 1200);
PAINT MONO (-2300 1200);
DISPLAY INVISIBLE (-2300 1200);
FORCEPROP 2 LAST BOM_COST SM_CONTROLLER
J 0
(-2350 1350);
DISPLAY 1.021277 (-2350 1350);
PAINT ORANGE (-2350 1350);
DISPLAY INVISIBLE (-2350 1350);
FORCEPROP 2 LAST SEC_TYPE 0402
J 0
(-2250 1425);
DISPLAY 1.021277 (-2250 1425);
PAINT ORANGE (-2250 1425);
DISPLAY INVISIBLE (-2250 1425);
FORCEPROP 2 LAST SEC 1
J 0
(-2250 1425);
DISPLAY 0.680851 (-2250 1425);
PAINT MONO (-2250 1425);
DISPLAY INVISIBLE (-2250 1425);
FORCEPROP 1 LAST PATH I153
J 0
(-2250 1375);
DISPLAY 0.978723 (-2250 1375);
PAINT WHITE (-2250 1375);
DISPLAY INVISIBLE (-2250 1375);
FORCEPROP 2 LAST CDS_LOCATION R9W33
J 0
(-2255 1325);
DISPLAY 0.617021 (-2255 1325);
PAINT AQUA (-2255 1325);
DISPLAY INVISIBLE (-2255 1325);
FORCEADD RES..2
(-2025 1200);
FORCEPROP 1 LASTPIN (-2025 1100) $PN 2
J 0
(-2020 1110);
DISPLAY 0.617021 (-2020 1110);
PAINT ORANGE (-2020 1110);
FORCEPROP 1 LAST VALUE 4.75K
J 0
(-1980 1275);
DISPLAY 0.617021 (-1980 1275);
PAINT SKYBLUE (-1980 1275);
FORCEPROP 1 LAST LOCATION R9W34
J 0
(-1980 1325);
DISPLAY 0.617021 (-1980 1325);
PAINT AQUA (-1980 1325);
FORCEPROP 1 LAST MATERIAL CHIP
J 0
(-1985 1125);
DISPLAY 0.617021 (-1985 1125);
PAINT SKYBLUE (-1985 1125);
FORCEPROP 1 LAST WATTAGE 1/16W
J 0
(-1985 1175);
DISPLAY 0.617021 (-1985 1175);
PAINT SKYBLUE (-1985 1175);
FORCEPROP 1 LAST TOLERANCE 1%
J 0
(-1980 1225);
DISPLAY 0.617021 (-1980 1225);
PAINT SKYBLUE (-1980 1225);
FORCEPROP 1 LASTPIN (-2025 1300) $PN 1
J 0
(-2020 1262);
DISPLAY 0.617021 (-2020 1262);
PAINT ORANGE (-2020 1262);
FORCEPROP 1 LAST PACK_TYPE 0402
J 0
(-1985 1025);
DISPLAY 0.617021 (-1985 1025);
PAINT SKYBLUE (-1985 1025);
FORCEPROP 0 LAST POP NOPOP
J 0
(-1975 975);
DISPLAY 0.638298 (-1975 975);
PAINT RED (-1975 975);
FORCEPROP 1 LAST PART_NUMBER G21796-072
J 0
(-1985 1075);
DISPLAY 0.617021 (-1985 1075);
PAINT BLUE (-1985 1075);
FORCEPROP 2 LAST ROOM BMC_MISC
J 0
(-2075 1300);
DISPLAY 1.021277 (-2075 1300);
PAINT ORANGE (-2075 1300);
DISPLAY INVISIBLE (-2075 1300);
FORCEPROP 2 LAST CDS_LIB mstr_discrete
J 0
(-2025 1200);
PAINT MONO (-2025 1200);
DISPLAY INVISIBLE (-2025 1200);
FORCEPROP 2 LAST BOM_COST SM_CONTROLLER
J 0
(-2075 1350);
DISPLAY 1.021277 (-2075 1350);
PAINT ORANGE (-2075 1350);
DISPLAY INVISIBLE (-2075 1350);
FORCEPROP 2 LAST SEC_TYPE 0402
J 0
(-1975 1425);
DISPLAY 1.021277 (-1975 1425);
PAINT ORANGE (-1975 1425);
DISPLAY INVISIBLE (-1975 1425);
FORCEPROP 2 LAST SEC 1
J 0
(-1975 1425);
DISPLAY 0.680851 (-1975 1425);
PAINT MONO (-1975 1425);
DISPLAY INVISIBLE (-1975 1425);
FORCEPROP 1 LAST PATH I154
J 0
(-1975 1375);
DISPLAY 0.978723 (-1975 1375);
PAINT WHITE (-1975 1375);
DISPLAY INVISIBLE (-1975 1375);
FORCEPROP 2 LAST CDS_LOCATION R9W34
J 0
(-1980 1325);
DISPLAY 0.617021 (-1980 1325);
PAINT AQUA (-1980 1325);
DISPLAY INVISIBLE (-1980 1325);
FORCEADD RES..2
(-1750 1200);
FORCEPROP 1 LASTPIN (-1750 1100) $PN 2
J 0
(-1745 1110);
DISPLAY 0.617021 (-1745 1110);
PAINT ORANGE (-1745 1110);
FORCEPROP 1 LASTPIN (-1750 1300) $PN 1
J 0
(-1745 1262);
DISPLAY 0.617021 (-1745 1262);
PAINT ORANGE (-1745 1262);
FORCEPROP 1 LAST TOLERANCE 1%
J 0
(-1705 1225);
DISPLAY 0.617021 (-1705 1225);
PAINT SKYBLUE (-1705 1225);
FORCEPROP 1 LAST LOCATION R9W35
J 0
(-1705 1325);
DISPLAY 0.617021 (-1705 1325);
PAINT AQUA (-1705 1325);
FORCEPROP 1 LAST VALUE 4.75K
J 0
(-1705 1275);
DISPLAY 0.617021 (-1705 1275);
PAINT SKYBLUE (-1705 1275);
FORCEPROP 1 LAST WATTAGE 1/16W
J 0
(-1710 1175);
DISPLAY 0.617021 (-1710 1175);
PAINT SKYBLUE (-1710 1175);
FORCEPROP 1 LAST MATERIAL CHIP
J 0
(-1710 1125);
DISPLAY 0.617021 (-1710 1125);
PAINT SKYBLUE (-1710 1125);
FORCEPROP 1 LAST PART_NUMBER G21796-072
J 0
(-1710 1075);
DISPLAY 0.617021 (-1710 1075);
PAINT BLUE (-1710 1075);
FORCEPROP 1 LAST PACK_TYPE 0402
J 0
(-1710 1025);
DISPLAY 0.617021 (-1710 1025);
PAINT SKYBLUE (-1710 1025);
FORCEPROP 0 LAST POP NOPOP
J 0
(-1700 975);
DISPLAY 0.638298 (-1700 975);
PAINT RED (-1700 975);
FORCEPROP 1 LAST PATH I155
J 0
(-1700 1375);
DISPLAY 0.978723 (-1700 1375);
PAINT WHITE (-1700 1375);
DISPLAY INVISIBLE (-1700 1375);
FORCEPROP 2 LAST SEC 1
J 0
(-1700 1425);
DISPLAY 0.680851 (-1700 1425);
PAINT MONO (-1700 1425);
DISPLAY INVISIBLE (-1700 1425);
FORCEPROP 2 LAST SEC_TYPE 0402
J 0
(-1700 1425);
DISPLAY 1.021277 (-1700 1425);
PAINT ORANGE (-1700 1425);
DISPLAY INVISIBLE (-1700 1425);
FORCEPROP 2 LAST BOM_COST SM_CONTROLLER
J 0
(-1800 1350);
DISPLAY 1.021277 (-1800 1350);
PAINT ORANGE (-1800 1350);
DISPLAY INVISIBLE (-1800 1350);
FORCEPROP 2 LAST CDS_LIB mstr_discrete
J 0
(-1750 1200);
PAINT MONO (-1750 1200);
DISPLAY INVISIBLE (-1750 1200);
FORCEPROP 2 LAST ROOM BMC_MISC
J 0
(-1800 1300);
DISPLAY 1.021277 (-1800 1300);
PAINT ORANGE (-1800 1300);
DISPLAY INVISIBLE (-1800 1300);
FORCEPROP 2 LAST CDS_LOCATION R9W35
J 0
(-1705 1325);
DISPLAY 0.617021 (-1705 1325);
PAINT AQUA (-1705 1325);
DISPLAY INVISIBLE (-1705 1325);
FORCEADD P3V3_STBY..1
(-2300 1650);
FORCEPROP 3 LASTPIN (-2300 1600) SIG_NAME P3V3_STBY\g
J 0
(-2290 1610);
DISPLAY 0.659574 (-2290 1610);
PAINT MONO (-2290 1610);
DISPLAY INVISIBLE (-2290 1610);
FORCEPROP 1 LAST PATH I156
J 0
(-2255 1652);
DISPLAY 0.340426 (-2255 1652);
PAINT GREEN (-2255 1652);
DISPLAY INVISIBLE (-2255 1652);
FORCEPROP 1 LAST VOLTAGE 3.3V
J 0
(-2345 1607);
DISPLAY 0.340426 (-2345 1607);
PAINT SKYBLUE (-2345 1607);
DISPLAY INVISIBLE (-2345 1607);
FORCEPROP 2 LAST CDS_LIB mstr_symbols
J 0
(-2300 1650);
PAINT MONO (-2300 1650);
DISPLAY INVISIBLE (-2300 1650);
FORCEPROP 1 LAST SIZE 1B
J 0
(-2255 1672);
DISPLAY 0.340426 (-2255 1672);
PAINT GREEN (-2255 1672);
DISPLAY INVISIBLE (-2255 1672);
FORCEPROP 1 LAST BODY_TYPE PLUMBING
J 0
(-2345 1607);
DISPLAY 0.340426 (-2345 1607);
PAINT GREEN (-2345 1607);
DISPLAY INVISIBLE (-2345 1607);
FORCEPROP 1 LAST HDL_POWER P3V3_STBY
J 0
(-2600 1525);
DISPLAY 0.872340 (-2600 1525);
PAINT ORANGE (-2600 1525);
DISPLAY INVISIBLE (-2600 1525);
FORCEADD CAP_A..1
(-1675 2950);
FORCEPROP 1 LAST PART_NUMBER A36096-030
J 0
(-1625 2800);
DISPLAY 0.617021 (-1625 2800);
PAINT BLUE (-1625 2800);
FORCEPROP 1 LAST PACK_TYPE 0402V
J 0
(-1625 2750);
DISPLAY 0.617021 (-1625 2750);
PAINT SKYBLUE (-1625 2750);
FORCEPROP 1 LASTPIN (-1675 3050) $PN 1
J 0
(-1665 3030);
DISPLAY 0.617021 (-1665 3030);
PAINT ORANGE (-1665 3030);
FORCEPROP 1 LASTPIN (-1675 2850) $PN 2
J 0
(-1665 2830);
DISPLAY 0.617021 (-1665 2830);
PAINT ORANGE (-1665 2830);
FORCEPROP 1 LAST MATERIAL X7R
J 0
(-1625 2850);
DISPLAY 0.617021 (-1625 2850);
PAINT SKYBLUE (-1625 2850);
FORCEPROP 1 LAST VOLTAGE 16V
J 0
(-1625 2950);
DISPLAY 0.617021 (-1625 2950);
PAINT SKYBLUE (-1625 2950);
FORCEPROP 1 LAST TOLERANCE 10%
J 0
(-1625 2900);
DISPLAY 0.617021 (-1625 2900);
PAINT SKYBLUE (-1625 2900);
FORCEPROP 1 LAST VALUE 0.1UF
J 0
(-1625 3000);
DISPLAY 0.617021 (-1625 3000);
PAINT SKYBLUE (-1625 3000);
FORCEPROP 1 LAST LOCATION C1T10
J 0
(-1625 3050);
DISPLAY 0.617021 (-1625 3050);
PAINT AQUA (-1625 3050);
FORCEPROP 2 LAST CDS_LIB dev_discrete
J 0
(-1675 2950);
PAINT ORANGE (-1675 2950);
DISPLAY INVISIBLE (-1675 2950);
FORCEPROP 2 LAST CDS_LOCATION C1T10
J 0
(-1625 3050);
DISPLAY 0.617021 (-1625 3050);
PAINT AQUA (-1625 3050);
DISPLAY INVISIBLE (-1625 3050);
FORCEPROP 1 LAST PATH I70
J 0
(-1625 3100);
DISPLAY 0.978723 (-1625 3100);
PAINT WHITE (-1625 3100);
DISPLAY INVISIBLE (-1625 3100);
FORCEPROP 2 LAST BOM_COST DEBUG
J 0
(-1625 3150);
DISPLAY 1.021277 (-1625 3150);
PAINT ORANGE (-1625 3150);
DISPLAY INVISIBLE (-1625 3150);
FORCEPROP 2 LAST CDS_SEC 1
J 0
(-1625 3100);
PAINT ORANGE (-1625 3100);
DISPLAY INVISIBLE (-1625 3100);
FORCEPROP 2 LAST SEC_TYPE 0402V
J 0
(-1625 3150);
DISPLAY 1.021277 (-1625 3150);
PAINT ORANGE (-1625 3150);
DISPLAY INVISIBLE (-1625 3150);
FORCEPROP 2 LAST SEC 1
J 0
(-1625 3150);
DISPLAY 0.680851 (-1625 3150);
PAINT MONO (-1625 3150);
DISPLAY INVISIBLE (-1625 3150);
FORCEPROP 2 LAST ROOM UART_MUX
J 0
(-1625 3100);
DISPLAY 1.021277 (-1625 3100);
PAINT ORANGE (-1625 3100);
DISPLAY INVISIBLE (-1625 3100);
FORCEADD GND..1
(-1675 2725);
FORCEPROP 3 LASTPIN (-1675 2775) SIG_NAME GND\g
J 0
(-1665 2785);
DISPLAY 0.659574 (-1665 2785);
PAINT MONO (-1665 2785);
DISPLAY INVISIBLE (-1665 2785);
FORCEPROP 1 LAST HDL_POWER GND
J 0
(-1675 2875);
DISPLAY 0.872340 (-1675 2875);
PAINT GREEN (-1675 2875);
DISPLAY INVISIBLE (-1675 2875);
FORCEPROP 1 LAST BODY_TYPE PLUMBING
J 0
(-1720 2682);
DISPLAY 0.340426 (-1720 2682);
PAINT GREEN (-1720 2682);
DISPLAY INVISIBLE (-1720 2682);
FORCEPROP 1 LAST VOLTAGE 0.0V
J 0
(-1720 2682);
DISPLAY 0.340426 (-1720 2682);
PAINT SKYBLUE (-1720 2682);
DISPLAY INVISIBLE (-1720 2682);
FORCEPROP 1 LAST PATH I72
J 0
(-1600 2725);
DISPLAY 0.872340 (-1600 2725);
PAINT AQUA (-1600 2725);
DISPLAY INVISIBLE (-1600 2725);
FORCEPROP 1 LAST SIZE 1B
J 0
(-1600 2675);
DISPLAY 0.872340 (-1600 2675);
PAINT AQUA (-1600 2675);
DISPLAY INVISIBLE (-1600 2675);
FORCEPROP 2 LAST CDS_LIB mstr_symbols
J 0
(-1675 2725);
PAINT ORANGE (-1675 2725);
DISPLAY INVISIBLE (-1675 2725);
FORCEADD FSA3357..1
R 2
(-2175 2575);
FORCEPROP 1 LAST LOCATION U9F2
J 2
(-1975 2975);
DISPLAY 0.617021 (-1975 2975);
PAINT AQUA (-1975 2975);
FORCEPROP 1 LAST PART_NUMBER C63273-001
J 2
(-1975 2225);
DISPLAY 0.617021 (-1975 2225);
PAINT BLUE (-1975 2225);
FORCEPROP 2 LASTPIN (-2425 2675) $PN 3
J 2
(-2435 2685);
DISPLAY 0.617021 (-2435 2685);
PAINT ORANGE (-2435 2685);
FORCEPROP 2 LASTPIN (-2425 2575) $PN 1
J 2
(-2435 2585);
DISPLAY 0.617021 (-2435 2585);
PAINT ORANGE (-2435 2585);
FORCEPROP 1 LAST MATERIAL IC
J 2
(-1975 2925);
DISPLAY 0.617021 (-1975 2925);
PAINT SKYBLUE (-1975 2925);
FORCEPROP 2 LASTPIN (-1925 2475) $PN 6
J 0
(-1915 2485);
DISPLAY 0.617021 (-1915 2485);
PAINT ORANGE (-1915 2485);
FORCEPROP 2 LASTPIN (-1925 2525) $PN 5
J 0
(-1915 2535);
DISPLAY 0.617021 (-1915 2535);
PAINT ORANGE (-1915 2535);
FORCEPROP 2 LASTPIN (-2425 2625) $PN 2
J 2
(-2435 2635);
DISPLAY 0.617021 (-2435 2635);
PAINT ORANGE (-2435 2635);
FORCEPROP 2 LASTPIN (-1925 2625) $PN 7
J 0
(-1915 2635);
DISPLAY 0.617021 (-1915 2635);
PAINT ORANGE (-1915 2635);
FORCEPROP 2 LASTPIN (-1925 2725) $PN 8
J 0
(-1915 2735);
DISPLAY 0.617021 (-1915 2735);
PAINT ORANGE (-1915 2735);
FORCEPROP 2 LASTPIN (-2425 2325) $PN 4
J 2
(-2435 2335);
DISPLAY 0.617021 (-2435 2335);
PAINT ORANGE (-2435 2335);
FORCEPROP 2 LAST CDS_LIB mstr_analog
J 2
(-2175 2575);
PAINT MONO (-2175 2575);
DISPLAY INVISIBLE (-2175 2575);
FORCEPROP 2 LAST SEC_TYPE SM
J 0
(-1975 3025);
DISPLAY 1.021277 (-1975 3025);
PAINT ORANGE (-1975 3025);
DISPLAY INVISIBLE (-1975 3025);
FORCEPROP 2 LAST SEC 1
J 0
(-1975 3025);
DISPLAY 0.680851 (-1975 3025);
PAINT MONO (-1975 3025);
DISPLAY INVISIBLE (-1975 3025);
FORCEPROP 2 LAST CDS_LOCATION U9F2
J 2
(-1975 2975);
DISPLAY 0.617021 (-1975 2975);
PAINT AQUA (-1975 2975);
DISPLAY INVISIBLE (-1975 2975);
FORCEPROP 1 LAST PATH I74
J 2
(-2175 2925);
PAINT GREEN (-2175 2925);
DISPLAY INVISIBLE (-2175 2925);
FORCEPROP 2 LAST ROOM UART_MUX
J 0
(-1975 3025);
DISPLAY 1.021277 (-1975 3025);
PAINT ORANGE (-1975 3025);
DISPLAY INVISIBLE (-1975 3025);
FORCEPROP 1 LAST PACK_TYPE SM
J 2
(-1975 3025);
PAINT SKYBLUE (-1975 3025);
DISPLAY INVISIBLE (-1975 3025);
FORCEPROP 2 LAST BOM_COST DEBUG
J 0
(-1975 3075);
DISPLAY 1.021277 (-1975 3075);
PAINT ORANGE (-1975 3075);
DISPLAY INVISIBLE (-1975 3075);
FORCEADD FSA3357..1
(-2650 850);
FORCEPROP 1 LAST MATERIAL IC
J 0
(-2850 1200);
DISPLAY 0.617021 (-2850 1200);
PAINT SKYBLUE (-2850 1200);
FORCEPROP 2 LASTPIN (-2900 1000) $PN 8
J 2
(-2910 1010);
DISPLAY 0.617021 (-2910 1010);
PAINT ORANGE (-2910 1010);
FORCEPROP 2 LASTPIN (-2400 900) $PN 2
J 0
(-2390 910);
DISPLAY 0.617021 (-2390 910);
PAINT ORANGE (-2390 910);
FORCEPROP 2 LASTPIN (-2400 600) $PN 4
J 0
(-2390 610);
DISPLAY 0.617021 (-2390 610);
PAINT ORANGE (-2390 610);
FORCEPROP 2 LASTPIN (-2900 750) $PN 6
J 2
(-2910 760);
DISPLAY 0.617021 (-2910 760);
PAINT ORANGE (-2910 760);
FORCEPROP 1 LAST LOCATION U9F1
J 0
(-2850 1250);
DISPLAY 0.617021 (-2850 1250);
PAINT AQUA (-2850 1250);
FORCEPROP 1 LAST PART_NUMBER C63273-001
J 0
(-2850 500);
DISPLAY 0.617021 (-2850 500);
PAINT BLUE (-2850 500);
FORCEPROP 2 LASTPIN (-2400 850) $PN 1
J 0
(-2390 860);
DISPLAY 0.617021 (-2390 860);
PAINT ORANGE (-2390 860);
FORCEPROP 2 LASTPIN (-2900 800) $PN 5
J 2
(-2910 810);
DISPLAY 0.617021 (-2910 810);
PAINT ORANGE (-2910 810);
FORCEPROP 2 LASTPIN (-2900 900) $PN 7
J 2
(-2910 910);
DISPLAY 0.617021 (-2910 910);
PAINT ORANGE (-2910 910);
FORCEPROP 2 LASTPIN (-2400 950) $PN 3
J 0
(-2390 960);
DISPLAY 0.617021 (-2390 960);
PAINT ORANGE (-2390 960);
FORCEPROP 1 LAST PATH I75
J 0
(-2650 1200);
PAINT GREEN (-2650 1200);
DISPLAY INVISIBLE (-2650 1200);
FORCEPROP 1 LAST PACK_TYPE SM
J 0
(-2850 1300);
PAINT SKYBLUE (-2850 1300);
DISPLAY INVISIBLE (-2850 1300);
FORCEPROP 2 LAST ROOM UART_MUX
J 0
(-2850 1300);
DISPLAY 1.021277 (-2850 1300);
PAINT ORANGE (-2850 1300);
DISPLAY INVISIBLE (-2850 1300);
FORCEPROP 2 LAST BOM_COST DEBUG
J 0
(-2850 1350);
DISPLAY 1.021277 (-2850 1350);
PAINT ORANGE (-2850 1350);
DISPLAY INVISIBLE (-2850 1350);
FORCEPROP 2 LAST CDS_LOCATION U9F1
J 0
(-2850 1250);
DISPLAY 0.617021 (-2850 1250);
PAINT AQUA (-2850 1250);
DISPLAY INVISIBLE (-2850 1250);
FORCEPROP 2 LAST SEC 1
J 0
(-2850 1300);
DISPLAY 0.680851 (-2850 1300);
PAINT MONO (-2850 1300);
DISPLAY INVISIBLE (-2850 1300);
FORCEPROP 2 LAST SEC_TYPE SM
J 0
(-2850 1300);
DISPLAY 1.021277 (-2850 1300);
PAINT ORANGE (-2850 1300);
DISPLAY INVISIBLE (-2850 1300);
FORCEPROP 2 LAST CDS_LIB mstr_analog
J 0
(-2650 850);
PAINT MONO (-2650 850);
DISPLAY INVISIBLE (-2650 850);
FORCEADD GND..1
(-2625 2125);
FORCEPROP 3 LASTPIN (-2625 2175) SIG_NAME GND\g
J 0
(-2615 2185);
DISPLAY 0.659574 (-2615 2185);
PAINT MONO (-2615 2185);
DISPLAY INVISIBLE (-2615 2185);
FORCEPROP 1 LAST HDL_POWER GND
J 0
(-2625 2275);
DISPLAY 0.872340 (-2625 2275);
PAINT GREEN (-2625 2275);
DISPLAY INVISIBLE (-2625 2275);
FORCEPROP 1 LAST BODY_TYPE PLUMBING
J 0
(-2670 2082);
DISPLAY 0.340426 (-2670 2082);
PAINT GREEN (-2670 2082);
DISPLAY INVISIBLE (-2670 2082);
FORCEPROP 1 LAST PATH I76
J 0
(-2550 2125);
DISPLAY 0.872340 (-2550 2125);
PAINT AQUA (-2550 2125);
DISPLAY INVISIBLE (-2550 2125);
FORCEPROP 1 LAST SIZE 1B
J 0
(-2550 2075);
DISPLAY 0.872340 (-2550 2075);
PAINT AQUA (-2550 2075);
DISPLAY INVISIBLE (-2550 2075);
FORCEPROP 1 LAST VOLTAGE 0.0V
J 0
(-2670 2082);
DISPLAY 0.340426 (-2670 2082);
PAINT SKYBLUE (-2670 2082);
DISPLAY INVISIBLE (-2670 2082);
FORCEPROP 2 LAST CDS_LIB mstr_symbols
J 0
(-2625 2125);
PAINT MONO (-2625 2125);
DISPLAY INVISIBLE (-2625 2125);
FORCEADD GND..1
(-2325 425);
FORCEPROP 3 LASTPIN (-2325 475) SIG_NAME GND\g
J 0
(-2315 485);
DISPLAY 0.659574 (-2315 485);
PAINT MONO (-2315 485);
DISPLAY INVISIBLE (-2315 485);
FORCEPROP 1 LAST HDL_POWER GND
J 0
(-2325 575);
DISPLAY 0.872340 (-2325 575);
PAINT GREEN (-2325 575);
DISPLAY INVISIBLE (-2325 575);
FORCEPROP 1 LAST BODY_TYPE PLUMBING
J 0
(-2370 382);
DISPLAY 0.340426 (-2370 382);
PAINT GREEN (-2370 382);
DISPLAY INVISIBLE (-2370 382);
FORCEPROP 1 LAST VOLTAGE 0.0V
J 0
(-2370 382);
DISPLAY 0.340426 (-2370 382);
PAINT SKYBLUE (-2370 382);
DISPLAY INVISIBLE (-2370 382);
FORCEPROP 1 LAST PATH I77
J 0
(-2250 425);
DISPLAY 0.872340 (-2250 425);
PAINT AQUA (-2250 425);
DISPLAY INVISIBLE (-2250 425);
FORCEPROP 1 LAST SIZE 1B
J 0
(-2250 375);
DISPLAY 0.872340 (-2250 375);
PAINT AQUA (-2250 375);
DISPLAY INVISIBLE (-2250 375);
FORCEPROP 2 LAST CDS_LIB mstr_symbols
J 0
(-2325 425);
PAINT MONO (-2325 425);
DISPLAY INVISIBLE (-2325 425);
FORCEADD P3V3_STBY..1
(-1850 3150);
FORCEPROP 3 LASTPIN (-1850 3100) SIG_NAME P3V3_STBY\g
J 0
(-1840 3110);
DISPLAY 0.659574 (-1840 3110);
PAINT MONO (-1840 3110);
DISPLAY INVISIBLE (-1840 3110);
FORCEPROP 1 LAST HDL_POWER P3V3_STBY
J 0
(-2150 3025);
DISPLAY 0.872340 (-2150 3025);
PAINT ORANGE (-2150 3025);
DISPLAY INVISIBLE (-2150 3025);
FORCEPROP 1 LAST BODY_TYPE PLUMBING
J 0
(-1895 3107);
DISPLAY 0.340426 (-1895 3107);
PAINT GREEN (-1895 3107);
DISPLAY INVISIBLE (-1895 3107);
FORCEPROP 1 LAST VOLTAGE 3.3V
J 0
(-1895 3107);
DISPLAY 0.340426 (-1895 3107);
PAINT SKYBLUE (-1895 3107);
DISPLAY INVISIBLE (-1895 3107);
FORCEPROP 2 LAST CDS_LIB mstr_symbols
J 0
(-1850 3150);
PAINT MONO (-1850 3150);
DISPLAY INVISIBLE (-1850 3150);
FORCEPROP 1 LAST PATH I78
J 0
(-1805 3152);
DISPLAY 0.340426 (-1805 3152);
PAINT GREEN (-1805 3152);
DISPLAY INVISIBLE (-1805 3152);
FORCEPROP 1 LAST SIZE 1B
J 0
(-1805 3172);
DISPLAY 0.340426 (-1805 3172);
PAINT GREEN (-1805 3172);
DISPLAY INVISIBLE (-1805 3172);
FORCEADD P3V3_STBY..1
(-3100 1425);
FORCEPROP 3 LASTPIN (-3100 1375) SIG_NAME P3V3_STBY\g
J 0
(-3090 1385);
DISPLAY 0.659574 (-3090 1385);
PAINT MONO (-3090 1385);
DISPLAY INVISIBLE (-3090 1385);
FORCEPROP 1 LAST PATH I79
J 0
(-3055 1427);
DISPLAY 0.340426 (-3055 1427);
PAINT GREEN (-3055 1427);
DISPLAY INVISIBLE (-3055 1427);
FORCEPROP 1 LAST HDL_POWER P3V3_STBY
J 0
(-3400 1300);
DISPLAY 0.872340 (-3400 1300);
PAINT ORANGE (-3400 1300);
DISPLAY INVISIBLE (-3400 1300);
FORCEPROP 1 LAST BODY_TYPE PLUMBING
J 0
(-3145 1382);
DISPLAY 0.340426 (-3145 1382);
PAINT GREEN (-3145 1382);
DISPLAY INVISIBLE (-3145 1382);
FORCEPROP 1 LAST SIZE 1B
J 0
(-3055 1447);
DISPLAY 0.340426 (-3055 1447);
PAINT GREEN (-3055 1447);
DISPLAY INVISIBLE (-3055 1447);
FORCEPROP 2 LAST CDS_LIB mstr_symbols
J 0
(-3100 1425);
PAINT MONO (-3100 1425);
DISPLAY INVISIBLE (-3100 1425);
FORCEPROP 1 LAST VOLTAGE 3.3V
J 0
(-3145 1382);
DISPLAY 0.340426 (-3145 1382);
PAINT SKYBLUE (-3145 1382);
DISPLAY INVISIBLE (-3145 1382);
FORCEADD OFFPAGE..2
(-600 2625);
FORCEPROP 2 LAST $XR1 181 
J 0
(-291 2625);
DISPLAY 0.638298 (-291 2625);
PAINT MONO (-291 2625);
FORCEPROP 2 LAST $XR0 176 
J 0
(-411 2625);
DISPLAY 0.638298 (-411 2625);
PAINT MONO (-411 2625);
FORCEPROP 1 LAST COMMENT_BODY TRUE
J 0
(-645 2530);
DISPLAY 0.872340 (-645 2530);
PAINT GREEN (-645 2530);
DISPLAY INVISIBLE (-645 2530);
FORCEPROP 1 LAST OFFPAGE TRUE
J 0
(-275 2500);
DISPLAY 0.872340 (-275 2500);
PAINT GREEN (-275 2500);
DISPLAY INVISIBLE (-275 2500);
FORCEPROP 2 LAST CDS_LIB mstr_standard
J 0
(-600 2625);
PAINT MONO (-600 2625);
DISPLAY INVISIBLE (-600 2625);
FORCEPROP 2 LAST PATH I85
J 0
(-550 2700);
DISPLAY 1.021277 (-550 2700);
PAINT ORANGE (-550 2700);
DISPLAY INVISIBLE (-550 2700);
FORCEADD RES..1
(-3625 900);
FORCEPROP 1 LAST WATTAGE 1/16W
J 2
(-3900 850);
DISPLAY 0.617021 (-3900 850);
PAINT SKYBLUE (-3900 850);
FORCEPROP 1 LAST MATERIAL CHIP
J 0
(-3675 850);
DISPLAY 0.617021 (-3675 850);
PAINT SKYBLUE (-3675 850);
FORCEPROP 1 LAST TOLERANCE 1%
J 0
(-3475 850);
DISPLAY 0.617021 (-3475 850);
PAINT SKYBLUE (-3475 850);
FORCEPROP 1 LASTPIN (-3525 900) $PN 2
J 0
(-3563 912);
DISPLAY 0.617021 (-3563 912);
PAINT ORANGE (-3563 912);
FORCEPROP 1 LAST LOCATION R9F25
J 0
(-3675 950);
DISPLAY 0.617021 (-3675 950);
PAINT AQUA (-3675 950);
FORCEPROP 1 LASTPIN (-3725 900) $PN 1
J 0
(-3713 912);
DISPLAY 0.617021 (-3713 912);
PAINT ORANGE (-3713 912);
FORCEPROP 1 LAST VALUE 100.0
J 2
(-3750 850);
DISPLAY 0.617021 (-3750 850);
PAINT SKYBLUE (-3750 850);
FORCEPROP 1 LAST PACK_TYPE 0402
J 0
(-3150 850);
DISPLAY 0.617021 (-3150 850);
PAINT SKYBLUE (-3150 850);
FORCEPROP 1 LAST PART_NUMBER G21796-017
J 0
(-3400 850);
DISPLAY 0.617021 (-3400 850);
PAINT BLUE (-3400 850);
FORCEPROP 2 LAST BOM_COST DEBUG
J 0
(-3625 1050);
DISPLAY 1.021277 (-3625 1050);
PAINT ORANGE (-3625 1050);
DISPLAY INVISIBLE (-3625 1050);
FORCEPROP 1 LAST PATH I86
J 0
(-3675 1050);
DISPLAY 0.978723 (-3675 1050);
PAINT WHITE (-3675 1050);
DISPLAY INVISIBLE (-3675 1050);
FORCEPROP 2 LAST SEC 1
J 0
(-3675 1100);
DISPLAY 0.680851 (-3675 1100);
PAINT MONO (-3675 1100);
DISPLAY INVISIBLE (-3675 1100);
FORCEPROP 2 LAST SEC_TYPE 0402
J 0
(-3675 1100);
DISPLAY 1.021277 (-3675 1100);
PAINT ORANGE (-3675 1100);
DISPLAY INVISIBLE (-3675 1100);
FORCEPROP 2 LAST ROOM UART_MUX
J 0
(-3625 1000);
DISPLAY 1.021277 (-3625 1000);
PAINT ORANGE (-3625 1000);
DISPLAY INVISIBLE (-3625 1000);
FORCEPROP 2 LAST CDS_LIB mstr_discrete
J 0
(-3625 900);
PAINT ORANGE (-3625 900);
DISPLAY INVISIBLE (-3625 900);
FORCEPROP 2 LAST CDS_LOCATION R9F25
J 0
(-3675 950);
DISPLAY 0.617021 (-3675 950);
PAINT AQUA (-3675 950);
DISPLAY INVISIBLE (-3675 950);
FORCEADD OFFPAGE..1
(-4725 900);
FORCEPROP 2 LAST $XR1 181 
J 0
(-5097 900);
DISPLAY 0.638298 (-5097 900);
PAINT MONO (-5097 900);
FORCEPROP 2 LAST $XR0 176 
J 0
(-4977 900);
DISPLAY 0.638298 (-4977 900);
PAINT MONO (-4977 900);
FORCEPROP 1 LAST COMMENT_BODY TRUE
J 0
(-4600 800);
DISPLAY 0.872340 (-4600 800);
PAINT GREEN (-4600 800);
DISPLAY INVISIBLE (-4600 800);
FORCEPROP 1 LAST OFFPAGE TRUE
J 0
(-4400 775);
DISPLAY 0.872340 (-4400 775);
PAINT GREEN (-4400 775);
DISPLAY INVISIBLE (-4400 775);
FORCEPROP 2 LAST CDS_LIB mstr_standard
J 0
(-4725 900);
PAINT MONO (-4725 900);
DISPLAY INVISIBLE (-4725 900);
FORCEPROP 2 LAST PATH I87
J 0
(-4675 975);
DISPLAY 1.021277 (-4675 975);
PAINT ORANGE (-4675 975);
DISPLAY INVISIBLE (-4675 975);
FORCEADD RES..1
(-1325 2625);
FORCEPROP 1 LAST VALUE 0.0
J 2
(-1350 2575);
DISPLAY 0.617021 (-1350 2575);
PAINT SKYBLUE (-1350 2575);
FORCEPROP 1 LAST PACK_TYPE 0402
J 0
(-1075 2575);
DISPLAY 0.617021 (-1075 2575);
PAINT SKYBLUE (-1075 2575);
FORCEPROP 1 LAST MATERIAL CHIP
J 0
(-1175 2575);
DISPLAY 0.617021 (-1175 2575);
PAINT SKYBLUE (-1175 2575);
FORCEPROP 1 LASTPIN (-1225 2625) $PN 2
J 0
(-1263 2637);
DISPLAY 0.617021 (-1263 2637);
PAINT ORANGE (-1263 2637);
FORCEPROP 1 LAST WATTAGE 1/16W
J 2
(-1425 2575);
DISPLAY 0.617021 (-1425 2575);
PAINT SKYBLUE (-1425 2575);
FORCEPROP 1 LAST PART_NUMBER G21497-005
J 0
(-1475 2500);
DISPLAY 0.617021 (-1475 2500);
PAINT BLUE (-1475 2500);
FORCEPROP 1 LASTPIN (-1425 2625) $PN 1
J 0
(-1413 2637);
DISPLAY 0.617021 (-1413 2637);
PAINT ORANGE (-1413 2637);
FORCEPROP 1 LAST LOCATION R9F27
J 0
(-1375 2675);
DISPLAY 0.617021 (-1375 2675);
PAINT AQUA (-1375 2675);
FORCEPROP 1 LAST TOLERANCE 5%
J 0
(-1250 2575);
DISPLAY 0.617021 (-1250 2575);
PAINT SKYBLUE (-1250 2575);
FORCEPROP 2 LAST SEC_TYPE 0402
J 0
(-1375 2825);
DISPLAY 1.021277 (-1375 2825);
PAINT ORANGE (-1375 2825);
DISPLAY INVISIBLE (-1375 2825);
FORCEPROP 2 LAST SEC 1
J 0
(-1375 2825);
PAINT MONO (-1375 2825);
DISPLAY INVISIBLE (-1375 2825);
FORCEPROP 2 LAST BOM_COST DEBUG
J 0
(-1325 2775);
DISPLAY 1.021277 (-1325 2775);
PAINT ORANGE (-1325 2775);
DISPLAY INVISIBLE (-1325 2775);
FORCEPROP 2 LAST CDS_LOCATION R9F27
J 0
(-1375 2675);
DISPLAY 0.617021 (-1375 2675);
PAINT AQUA (-1375 2675);
DISPLAY INVISIBLE (-1375 2675);
FORCEPROP 2 LAST CDS_LIB mstr_discrete
J 0
(-1325 2625);
PAINT MONO (-1325 2625);
DISPLAY INVISIBLE (-1325 2625);
FORCEPROP 1 LAST PATH I91
J 0
(-1375 2775);
DISPLAY 0.978723 (-1375 2775);
PAINT WHITE (-1375 2775);
DISPLAY INVISIBLE (-1375 2775);
FORCEPROP 2 LAST ROOM UART_MUX
J 0
(-1325 2725);
DISPLAY 1.021277 (-1325 2725);
PAINT ORANGE (-1325 2725);
DISPLAY INVISIBLE (-1325 2725);
FORCEADD OFFPAGE..1
(-4725 800);
FORCEPROP 2 LAST $XR3 158 
J 0
(-5337 800);
DISPLAY 0.638298 (-5337 800);
PAINT MONO (-5337 800);
FORCEPROP 2 LAST $XR2 144 
J 0
(-5217 800);
DISPLAY 0.638298 (-5217 800);
PAINT MONO (-5217 800);
FORCEPROP 2 LAST $XR1 120 
J 0
(-5097 800);
DISPLAY 0.638298 (-5097 800);
PAINT MONO (-5097 800);
FORCEPROP 2 LAST $XR0 190 
J 0
(-4977 800);
DISPLAY 0.638298 (-4977 800);
PAINT MONO (-4977 800);
FORCEPROP 1 LAST COMMENT_BODY TRUE
J 0
(-4600 700);
DISPLAY 0.872340 (-4600 700);
PAINT GREEN (-4600 700);
DISPLAY INVISIBLE (-4600 700);
FORCEPROP 1 LAST OFFPAGE TRUE
J 0
(-4400 675);
DISPLAY 0.872340 (-4400 675);
PAINT GREEN (-4400 675);
DISPLAY INVISIBLE (-4400 675);
FORCEPROP 2 LAST CDS_LIB mstr_standard
J 0
(-4725 800);
PAINT ORANGE (-4725 800);
DISPLAY INVISIBLE (-4725 800);
FORCEPROP 2 LAST PATH I92
J 0
(-5000 850);
DISPLAY 1.021277 (-5000 850);
PAINT ORANGE (-5000 850);
DISPLAY INVISIBLE (-5000 850);
FORCEADD OFFPAGE..1
(-4725 750);
FORCEPROP 2 LAST $XR3 158 
J 0
(-5337 750);
DISPLAY 0.638298 (-5337 750);
PAINT MONO (-5337 750);
FORCEPROP 2 LAST $XR2 144 
J 0
(-5217 750);
DISPLAY 0.638298 (-5217 750);
PAINT MONO (-5217 750);
FORCEPROP 2 LAST $XR1 120 
J 0
(-5097 750);
DISPLAY 0.638298 (-5097 750);
PAINT MONO (-5097 750);
FORCEPROP 2 LAST $XR0 190 
J 0
(-4977 750);
DISPLAY 0.638298 (-4977 750);
PAINT MONO (-4977 750);
FORCEPROP 1 LAST COMMENT_BODY TRUE
J 0
(-4600 650);
DISPLAY 0.872340 (-4600 650);
PAINT GREEN (-4600 650);
DISPLAY INVISIBLE (-4600 650);
FORCEPROP 1 LAST OFFPAGE TRUE
J 0
(-4400 625);
DISPLAY 0.872340 (-4400 625);
PAINT GREEN (-4400 625);
DISPLAY INVISIBLE (-4400 625);
FORCEPROP 2 LAST CDS_LIB mstr_standard
J 0
(-4725 750);
PAINT ORANGE (-4725 750);
DISPLAY INVISIBLE (-4725 750);
FORCEPROP 2 LAST PATH I93
J 0
(-5000 800);
DISPLAY 1.021277 (-5000 800);
PAINT ORANGE (-5000 800);
DISPLAY INVISIBLE (-5000 800);
FORCEADD OFFPAGE..1
(-3500 1975);
FORCEPROP 2 LAST $XR3 158 
J 0
(-4112 1975);
DISPLAY 0.638298 (-4112 1975);
PAINT MONO (-4112 1975);
FORCEPROP 2 LAST $XR2 144 
J 0
(-3992 1975);
DISPLAY 0.638298 (-3992 1975);
PAINT MONO (-3992 1975);
FORCEPROP 2 LAST $XR1 120 
J 0
(-3872 1975);
DISPLAY 0.638298 (-3872 1975);
PAINT MONO (-3872 1975);
FORCEPROP 2 LAST $XR0 190 
J 0
(-3752 1975);
DISPLAY 0.638298 (-3752 1975);
PAINT MONO (-3752 1975);
FORCEPROP 1 LAST COMMENT_BODY TRUE
J 0
(-3375 1875);
DISPLAY 0.872340 (-3375 1875);
PAINT GREEN (-3375 1875);
DISPLAY INVISIBLE (-3375 1875);
FORCEPROP 1 LAST OFFPAGE TRUE
J 0
(-3175 1850);
DISPLAY 0.872340 (-3175 1850);
PAINT GREEN (-3175 1850);
DISPLAY INVISIBLE (-3175 1850);
FORCEPROP 2 LAST PATH I94
J 0
(-3775 2025);
DISPLAY 1.021277 (-3775 2025);
PAINT ORANGE (-3775 2025);
DISPLAY INVISIBLE (-3775 2025);
FORCEPROP 2 LAST CDS_LIB mstr_standard
J 0
(-3500 1975);
PAINT ORANGE (-3500 1975);
DISPLAY INVISIBLE (-3500 1975);
FORCEADD OFFPAGE..1
(-3500 2025);
FORCEPROP 2 LAST $XR3 158 
J 0
(-4112 2025);
DISPLAY 0.638298 (-4112 2025);
PAINT MONO (-4112 2025);
FORCEPROP 2 LAST $XR2 144 
J 0
(-3992 2025);
DISPLAY 0.638298 (-3992 2025);
PAINT MONO (-3992 2025);
FORCEPROP 2 LAST $XR1 120 
J 0
(-3872 2025);
DISPLAY 0.638298 (-3872 2025);
PAINT MONO (-3872 2025);
FORCEPROP 2 LAST $XR0 190 
J 0
(-3752 2025);
DISPLAY 0.638298 (-3752 2025);
PAINT MONO (-3752 2025);
FORCEPROP 1 LAST COMMENT_BODY TRUE
J 0
(-3375 1925);
DISPLAY 0.872340 (-3375 1925);
PAINT GREEN (-3375 1925);
DISPLAY INVISIBLE (-3375 1925);
FORCEPROP 1 LAST OFFPAGE TRUE
J 0
(-3175 1900);
DISPLAY 0.872340 (-3175 1900);
PAINT GREEN (-3175 1900);
DISPLAY INVISIBLE (-3175 1900);
FORCEPROP 2 LAST PATH I95
J 0
(-3775 2075);
DISPLAY 1.021277 (-3775 2075);
PAINT ORANGE (-3775 2075);
DISPLAY INVISIBLE (-3775 2075);
FORCEPROP 2 LAST CDS_LIB mstr_standard
J 0
(-3500 2025);
PAINT ORANGE (-3500 2025);
DISPLAY INVISIBLE (-3500 2025);
FORCEADD CAP_A..1
(-3475 1200);
FORCEPROP 1 LAST VOLTAGE 16V
J 0
(-3425 1200);
DISPLAY 0.617021 (-3425 1200);
PAINT SKYBLUE (-3425 1200);
FORCEPROP 1 LAST PART_NUMBER A36096-030
J 0
(-3425 1050);
DISPLAY 0.617021 (-3425 1050);
PAINT BLUE (-3425 1050);
FORCEPROP 1 LAST LOCATION C1T11
J 0
(-3425 1300);
DISPLAY 0.617021 (-3425 1300);
PAINT AQUA (-3425 1300);
FORCEPROP 1 LAST VALUE 0.1UF
J 0
(-3425 1250);
DISPLAY 0.617021 (-3425 1250);
PAINT SKYBLUE (-3425 1250);
FORCEPROP 1 LASTPIN (-3475 1300) $PN 1
J 0
(-3465 1280);
DISPLAY 0.617021 (-3465 1280);
PAINT ORANGE (-3465 1280);
FORCEPROP 1 LAST TOLERANCE 10%
J 0
(-3425 1150);
DISPLAY 0.617021 (-3425 1150);
PAINT SKYBLUE (-3425 1150);
FORCEPROP 1 LAST MATERIAL X7R
J 0
(-3425 1100);
DISPLAY 0.617021 (-3425 1100);
PAINT SKYBLUE (-3425 1100);
FORCEPROP 1 LASTPIN (-3475 1100) $PN 2
J 0
(-3465 1080);
DISPLAY 0.617021 (-3465 1080);
PAINT ORANGE (-3465 1080);
FORCEPROP 1 LAST PACK_TYPE 0402V
J 0
(-3425 1000);
DISPLAY 0.617021 (-3425 1000);
PAINT SKYBLUE (-3425 1000);
FORCEPROP 2 LAST ROOM UART_MUX
J 0
(-3425 1350);
DISPLAY 1.021277 (-3425 1350);
PAINT ORANGE (-3425 1350);
DISPLAY INVISIBLE (-3425 1350);
FORCEPROP 2 LAST SEC 1
J 0
(-3425 1400);
DISPLAY 0.680851 (-3425 1400);
PAINT MONO (-3425 1400);
DISPLAY INVISIBLE (-3425 1400);
FORCEPROP 2 LAST CDS_LOCATION C1T11
J 0
(-3425 1300);
DISPLAY 0.617021 (-3425 1300);
PAINT AQUA (-3425 1300);
DISPLAY INVISIBLE (-3425 1300);
FORCEPROP 1 LAST PATH I97
J 0
(-3425 1350);
DISPLAY 0.978723 (-3425 1350);
PAINT WHITE (-3425 1350);
DISPLAY INVISIBLE (-3425 1350);
FORCEPROP 2 LAST CDS_SEC 1
J 0
(-3425 1350);
PAINT ORANGE (-3425 1350);
DISPLAY INVISIBLE (-3425 1350);
FORCEPROP 2 LAST BOM_COST DEBUG
J 0
(-3425 1400);
DISPLAY 1.021277 (-3425 1400);
PAINT ORANGE (-3425 1400);
DISPLAY INVISIBLE (-3425 1400);
FORCEPROP 2 LAST SEC_TYPE 0402V
J 0
(-3425 1400);
DISPLAY 1.021277 (-3425 1400);
PAINT ORANGE (-3425 1400);
DISPLAY INVISIBLE (-3425 1400);
FORCEPROP 2 LAST CDS_LIB dev_discrete
J 0
(-3475 1200);
PAINT ORANGE (-3475 1200);
DISPLAY INVISIBLE (-3475 1200);
FORCEADD GND..1
(-3475 1000);
FORCEPROP 3 LASTPIN (-3475 1050) SIG_NAME GND\g
J 0
(-3465 1060);
DISPLAY 0.659574 (-3465 1060);
PAINT MONO (-3465 1060);
DISPLAY INVISIBLE (-3465 1060);
FORCEPROP 1 LAST HDL_POWER GND
J 0
(-3475 1150);
DISPLAY 0.872340 (-3475 1150);
PAINT GREEN (-3475 1150);
DISPLAY INVISIBLE (-3475 1150);
FORCEPROP 1 LAST BODY_TYPE PLUMBING
J 0
(-3520 957);
DISPLAY 0.340426 (-3520 957);
PAINT GREEN (-3520 957);
DISPLAY INVISIBLE (-3520 957);
FORCEPROP 1 LAST PATH I98
J 0
(-3400 1000);
DISPLAY 0.872340 (-3400 1000);
PAINT AQUA (-3400 1000);
DISPLAY INVISIBLE (-3400 1000);
FORCEPROP 2 LAST CDS_LIB mstr_symbols
J 0
(-3475 1000);
PAINT ORANGE (-3475 1000);
DISPLAY INVISIBLE (-3475 1000);
FORCEPROP 1 LAST VOLTAGE 0.0V
J 0
(-3520 957);
DISPLAY 0.340426 (-3520 957);
PAINT SKYBLUE (-3520 957);
DISPLAY INVISIBLE (-3520 957);
FORCEPROP 1 LAST SIZE 1B
J 0
(-3400 950);
DISPLAY 0.872340 (-3400 950);
PAINT AQUA (-3400 950);
DISPLAY INVISIBLE (-3400 950);
FORCEADD RES..1
(-1900 3450);
FORCEPROP 1 LAST MATERIAL EMPTY
J 0
(-1900 3300);
DISPLAY 0.617021 (-1900 3300);
PAINT RED (-1900 3300);
FORCEPROP 1 LAST PART_NUMBER G21497-005
J 0
(-2000 3250);
DISPLAY 0.617021 (-2000 3250);
PAINT BLUE (-2000 3250);
FORCEPROP 1 LAST PACK_TYPE 0402
J 0
(-1650 3300);
DISPLAY 0.617021 (-1650 3300);
PAINT SKYBLUE (-1650 3300);
FORCEPROP 1 LAST LOCATION R9F26
J 0
(-1950 3500);
DISPLAY 0.617021 (-1950 3500);
PAINT AQUA (-1950 3500);
FORCEPROP 1 LAST WATTAGE 1/16W
J 2
(-1925 3300);
DISPLAY 0.617021 (-1925 3300);
PAINT SKYBLUE (-1925 3300);
FORCEPROP 1 LAST VALUE 0.0
J 2
(-1925 3350);
DISPLAY 0.617021 (-1925 3350);
PAINT SKYBLUE (-1925 3350);
FORCEPROP 1 LAST TOLERANCE 5%
J 0
(-1900 3350);
DISPLAY 0.617021 (-1900 3350);
PAINT SKYBLUE (-1900 3350);
FORCEPROP 1 LASTPIN (-2000 3450) $PN 1
J 0
(-1988 3462);
DISPLAY 0.617021 (-1988 3462);
PAINT ORANGE (-1988 3462);
FORCEPROP 1 LASTPIN (-1800 3450) $PN 2
J 0
(-1838 3462);
DISPLAY 0.617021 (-1838 3462);
PAINT ORANGE (-1838 3462);
FORCEPROP 2 LAST ROOM UART_MUX
J 0
(-1950 3550);
DISPLAY 1.021277 (-1950 3550);
PAINT ORANGE (-1950 3550);
DISPLAY INVISIBLE (-1950 3550);
FORCEPROP 2 LAST BOM_COST DEBUG
J 0
(-1950 3600);
DISPLAY 1.021277 (-1950 3600);
PAINT ORANGE (-1950 3600);
DISPLAY INVISIBLE (-1950 3600);
FORCEPROP 1 LAST PATH I99
J 0
(-1950 3600);
DISPLAY 0.978723 (-1950 3600);
PAINT WHITE (-1950 3600);
DISPLAY INVISIBLE (-1950 3600);
FORCEPROP 2 LAST SEC_TYPE 0402
J 0
(-1950 3650);
DISPLAY 1.021277 (-1950 3650);
PAINT ORANGE (-1950 3650);
DISPLAY INVISIBLE (-1950 3650);
FORCEPROP 2 LAST SEC 1
J 0
(-1950 3650);
DISPLAY 0.680851 (-1950 3650);
PAINT MONO (-1950 3650);
DISPLAY INVISIBLE (-1950 3650);
FORCEPROP 2 LAST CDS_LOCATION R9F26
J 0
(-1950 3500);
DISPLAY 0.617021 (-1950 3500);
PAINT AQUA (-1950 3500);
DISPLAY INVISIBLE (-1950 3500);
FORCEPROP 2 LAST CDS_LIB mstr_discrete
J 0
(-1900 3450);
PAINT ORANGE (-1900 3450);
DISPLAY INVISIBLE (-1900 3450);
FORCEADD DNS..2
(-2645 1520);
PAINT RED (-2645 1520);
FORCEPROP 1 LAST COMMENT_BODY TRUE
R 1
J 0
(-2570 1295);
DISPLAY 0.872340 (-2570 1295);
PAINT GREEN (-2570 1295);
DISPLAY INVISIBLE (-2570 1295);
FORCEPROP 2 LAST CDS_LIB mstr_misc
J 0
(-2645 1520);
PAINT ORANGE (-2645 1520);
DISPLAY INVISIBLE (-2645 1520);
FORCEADD CAD_NOTE..1
(-7725 4800);
FORCEPROP 0 LAST L4 THE LEFT OF THE LSB LED
J 0
(-7875 4475);
DISPLAY 1.021277 (-7875 4475);
PAINT ORANGE (-7875 4475);
FORCEPROP 0 LAST L1 PLACE LEDS NEAR BOARD EDGE NEXT TO BMC DEBUG
J 0
(-7875 4700);
DISPLAY 1.021277 (-7875 4700);
PAINT ORANGE (-7875 4700);
FORCEPROP 0 LAST L3 LEFT OF THE BMC DEBUG CONNECTOR. PLACE MSB LED ON
J 0
(-7875 4550);
DISPLAY 1.021277 (-7875 4550);
PAINT ORANGE (-7875 4550);
FORCEPROP 0 LAST L2 HEADER. WHEN LOOKING FROM BOARD EDGE, PLACE BOTH LEDS TO THE
J 0
(-7875 4625);
DISPLAY 1.021277 (-7875 4625);
PAINT ORANGE (-7875 4625);
FORCEPROP 1 LAST COMMENT_BODY TRUE
J 0
(-7700 4900);
DISPLAY 0.978723 (-7700 4900);
PAINT ORANGE (-7700 4900);
DISPLAY INVISIBLE (-7700 4900);
FORCEPROP 2 LAST CDS_LIB mstr_symbols
J 0
(-7725 4800);
PAINT MONO (-7725 4800);
DISPLAY INVISIBLE (-7725 4800);
FORCEADD DESIGN_NOTE..1
(-5675 4350);
FORCEPROP 0 LAST L3 00 DISCONNECTS THE OUTPUT FROM THE INPUTS ON THE
J 0
(-5875 4125);
DISPLAY 0.808511 (-5875 4125);
PAINT ORANGE (-5875 4125);
FORCEPROP 0 LAST L5 WERE 11
J 0
(-5875 4025);
DISPLAY 0.808511 (-5875 4025);
PAINT ORANGE (-5875 4025);
FORCEPROP 0 LAST L2 TO MEET LEGACY REQUIREMENTS. THIS IS BECAUSE
J 0
(-5875 4175);
DISPLAY 0.808511 (-5875 4175);
PAINT ORANGE (-5875 4175);
FORCEPROP 0 LAST L4 FSA3357, WHILE PAST MUXES DID THIS WHEN S1 AND S2
J 0
(-5875 4075);
DISPLAY 0.808511 (-5875 4075);
PAINT ORANGE (-5875 4075);
FORCEPROP 0 LAST L1 LED VALUES THE OPPOSITE OF MUX SELECT BITS
J 0
(-5875 4225);
DISPLAY 0.808511 (-5875 4225);
PAINT ORANGE (-5875 4225);
FORCEPROP 1 LAST COMMENT_BODY TRUE
J 0
(-5650 4450);
DISPLAY 0.978723 (-5650 4450);
PAINT ORANGE (-5650 4450);
DISPLAY INVISIBLE (-5650 4450);
FORCEPROP 2 LAST CDS_LIB mstr_symbols
J 0
(-5675 4350);
PAINT ORANGE (-5675 4350);
DISPLAY INVISIBLE (-5675 4350);
FORCEADD DNS..2
(-1245 845);
PAINT RED (-1245 845);
FORCEPROP 1 LAST COMMENT_BODY TRUE
R 1
J 0
(-1170 620);
DISPLAY 0.872340 (-1170 620);
PAINT GREEN (-1170 620);
DISPLAY INVISIBLE (-1170 620);
FORCEPROP 2 LAST CDS_LIB mstr_misc
J 0
(-1245 845);
PAINT ORANGE (-1245 845);
DISPLAY INVISIBLE (-1245 845);
FORCEADD CAD_NOTE..1
(-3725 4075);
FORCEPROP 0 LAST L2 ON NET SP2_BMC_CM_UART_TX_R
J 0
(-3875 3875);
DISPLAY 0.808511 (-3875 3875);
PAINT ORANGE (-3875 3875);
FORCEPROP 0 LAST L1 USE SHARED PADS FOR RESISTORS
J 0
(-3875 3950);
DISPLAY 0.808511 (-3875 3950);
PAINT ORANGE (-3875 3950);
FORCEPROP 1 LAST COMMENT_BODY TRUE
J 0
(-3700 4175);
DISPLAY 0.978723 (-3700 4175);
PAINT ORANGE (-3700 4175);
DISPLAY INVISIBLE (-3700 4175);
FORCEPROP 2 LAST CDS_LIB mstr_symbols
J 0
(-3725 4075);
PAINT ORANGE (-3725 4075);
DISPLAY INVISIBLE (-3725 4075);
FORCEADD CAD_NOTE..1
(-1350 2200);
FORCEPROP 0 LAST L1 USE SHARED PADS FOR RESISTORS
J 0
(-1500 2075);
DISPLAY 0.808511 (-1500 2075);
PAINT ORANGE (-1500 2075);
FORCEPROP 0 LAST L2 ON NET SP2_BMC_CM_UART_RX_R
J 0
(-1500 2000);
DISPLAY 0.808511 (-1500 2000);
PAINT ORANGE (-1500 2000);
FORCEPROP 1 LAST COMMENT_BODY TRUE
J 0
(-1325 2300);
DISPLAY 0.978723 (-1325 2300);
PAINT ORANGE (-1325 2300);
DISPLAY INVISIBLE (-1325 2300);
FORCEPROP 2 LAST CDS_LIB mstr_symbols
J 0
(-1350 2200);
PAINT ORANGE (-1350 2200);
DISPLAY INVISIBLE (-1350 2200);
FORCEADD DNS..2
(-1895 3445);
PAINT RED (-1895 3445);
FORCEPROP 1 LAST COMMENT_BODY TRUE
R 1
J 0
(-1820 3220);
DISPLAY 0.872340 (-1820 3220);
PAINT GREEN (-1820 3220);
DISPLAY INVISIBLE (-1820 3220);
FORCEPROP 2 LAST CDS_LIB mstr_misc
J 0
(-1895 3445);
PAINT MONO (-1895 3445);
DISPLAY INVISIBLE (-1895 3445);
FORCEADD DNS..2
(-3145 2595);
PAINT RED (-3145 2595);
FORCEPROP 1 LAST COMMENT_BODY TRUE
R 1
J 0
(-3070 2370);
DISPLAY 0.872340 (-3070 2370);
PAINT GREEN (-3070 2370);
DISPLAY INVISIBLE (-3070 2370);
FORCEPROP 2 LAST CDS_LIB mstr_misc
J 0
(-3145 2595);
PAINT ORANGE (-3145 2595);
DISPLAY INVISIBLE (-3145 2595);
FORCEADD INTEL_CORP_BPAGE..1
(0 0);
FORCEPROP 1 LAST CDS_CON_LAST_MODIFIED Fri Jun 16 17:48:59 2017
J 0
(-1425 325);
DISPLAY 1.361702 (-1425 325);
PAINT GREEN (-1425 325);
DISPLAY INVISIBLE (-1425 325);
FORCEPROP 1 LAST CUSTOM_TXT_CDS <CURRENT_DESIGN_SHEET> OF <TOTAL_DESIGN_SHEETS>
J 0
(-500 25);
PAINT ORANGE (-500 25);
FORCEPROP 1 LAST CUSTOM_TXT_CDS <CON_LAST_MODIFIED>
J 0
(-4000 100);
PAINT ORANGE (-4000 100);
FORCEPROP 2 LAST CUSTOM_TXT_CDS <XR_PAGE_TITLE>
J 0
(-7890 5250);
DISPLAY 0.638298 (-7890 5250);
PAINT PINK (-7890 5250);
DISPLAY INVISIBLE (-7890 5250);
FORCEPROP 1 LAST SCH_TITLE UART MUX
J 0
(-7950 50);
DISPLAY 1.212766 (-7950 50);
PAINT ORANGE (-7950 50);
FORCEPROP 1 LAST COMMENT_BODY TRUE
J 0
(12 12);
DISPLAY 0.617021 (12 12);
PAINT GREEN (12 12);
DISPLAY INVISIBLE (12 12);
FORCEPROP 2 LAST CDS_LIB mstr_symbols
J 0
(0 0);
DISPLAY 1.361702 (0 0);
PAINT ORANGE (0 0);
DISPLAY INVISIBLE (0 0);
FORCEPROP 2 LAST PAGE_BORDER TRUE
J 0
(-7890 5250);
DISPLAY 0.851064 (-7890 5250);
PAINT PINK (-7890 5250);
DISPLAY INVISIBLE (-7890 5250);
FORCEPROP 2 LAST CDS_XR_PAGE_TITLE CR-158 : @BASEBOARD_FAB2_LIB.BASEBOARD_FAB2(SCH_1):PAGE158
J 0
(-7890 5250);
DISPLAY 0.638298 (-7890 5250);
PAINT PINK (-7890 5250);
DISPLAY INVISIBLE (-7890 5250);
WIRE 16 -1 (-4400 3800)(-4400 3600);
WIRE 16 -1 (-4400 3200)(-4400 3600);
WIRE 16 -1 (-4400 3600)(-4775 3600);
WIRE 16 -1 (-4400 3200)(-4775 3200);
WIRE 16 -1 (-2300 1400)(-2300 1600);
WIRE 16 -1 (-2300 1400)(-2025 1400);
WIRE 16 -1 (-2300 1300)(-2300 1400);
WIRE 16 -1 (-2025 1400)(-1750 1400);
WIRE 16 -1 (-2025 1400)(-2025 1300);
WIRE 16 -1 (-1750 1400)(-1750 1300);
WIRE 16 -1 (-1675 2850)(-1675 2775);
WIRE 16 -1 (-2625 2175)(-2625 2325);
WIRE 16 -1 (-2625 2325)(-2425 2325);
WIRE 16 -1 (-2325 475)(-2325 600);
WIRE 16 -1 (-2325 600)(-2400 600);
WIRE 16 -1 (-1850 3100)(-1850 3075);
WIRE 16 -1 (-1850 3075)(-1850 2725);
WIRE 16 -1 (-1850 3075)(-1675 3075);
WIRE 16 -1 (-1675 3050)(-1675 3075);
WIRE 16 -1 (-1850 2725)(-1925 2725);
WIRE 16 -1 (-3100 1375)(-3100 1350);
WIRE 16 -1 (-3100 1350)(-3100 1000);
WIRE 16 -1 (-3475 1350)(-3100 1350);
WIRE 16 -1 (-3475 1300)(-3475 1350);
WIRE 16 -1 (-3100 1000)(-2900 1000);
WIRE 16 -1 (-3475 1100)(-3475 1050);
WIRE 16 -1 (-1750 850)(-2400 850);
FORCEPROP 2 LAST SIG_NAME SP2_BMC_CM_UART_RX_R
J 0
(-2335 860);
DISPLAY 0.617021 (-2335 860);
PAINT ORANGE (-2335 860);
FORCEPROP 2 LASTPROP $XRERR UNIQUE?
J 0
(-2575 860);
DISPLAY 0.638298 (-2575 860);
PAINT MONO (-2575 860);
DISPLAY INVISIBLE (-2575 860);
WIRE 16 -1 (-1750 1100)(-1750 850);
WIRE 16 -1 (-1375 1775)(-1200 1775);
WIRE 16 -1 (-1375 850)(-1750 850);
WIRE 16 -1 (-1350 850)(-1375 850);
WIRE 16 -1 (-1375 850)(-1375 1775);
WIRE 3 682 (-1600 1425)(-2425 1425);
WIRE 3 682 (-1600 800)(-1600 1425);
WIRE 3 682 (-2425 1425)(-2425 800);
WIRE 3 682 (-2425 800)(-1600 800);
WIRE 3 2175 (-1550 500)(-125 500);
WIRE 3 2175 (-125 1925)(-125 500);
WIRE 3 2175 (-1550 1925)(-1550 500);
WIRE 3 2175 (-1550 1925)(-125 1925);
WIRE 16 -1 (-1150 850)(-1075 850);
WIRE 16 -1 (-1075 850)(-450 850);
FORCEPROP 2 LAST SIG_NAME SP2_BMC_CM_UART_RX
J 2
(-575 860);
DISPLAY 0.617021 (-575 860);
PAINT ORANGE (-575 860);
WIRE 16 -1 (-1075 1525)(-2550 1525);
WIRE 16 -1 (-1075 1525)(-1075 850);
WIRE 16 -1 (-2400 900)(-2025 900);
WIRE 16 -1 (-2025 1100)(-2025 900);
WIRE 16 -1 (-2025 900)(-450 900);
FORCEPROP 2 LAST SIG_NAME UART_BMC_RXD5
J 2
(-700 910);
DISPLAY 0.617021 (-700 910);
PAINT ORANGE (-700 910);
WIRE 16 -1 (-2400 950)(-2300 950);
WIRE 16 -1 (-2300 1100)(-2300 950);
WIRE 16 -1 (-2300 950)(-450 950);
FORCEPROP 2 LAST SIG_NAME SP1_BMC_HOST_UART_RX
J 2
(-635 960);
DISPLAY 0.617021 (-635 960);
PAINT ORANGE (-635 960);
WIRE 16 -1 (-1000 1775)(-525 1775);
FORCEPROP 2 LAST SIG_NAME SP2_BMC_CM_UART_RX_R1
J 0
(-960 1785);
DISPLAY 0.617021 (-960 1785);
PAINT ORANGE (-960 1785);
WIRE 16 -1 (-3525 900)(-2900 900);
FORCEPROP 2 LAST SIG_NAME UART_MUX_IN_R
J 0
(-3485 910);
DISPLAY 0.617021 (-3485 910);
PAINT ORANGE (-3485 910);
FORCEPROP 2 LASTPROP $XRERR UNIQUE?
J 0
(-3725 910);
DISPLAY 0.638298 (-3725 910);
PAINT MONO (-3725 910);
DISPLAY INVISIBLE (-3725 910);
WIRE 16 -1 (-4675 800)(-2900 800);
FORCEPROP 2 LAST SIG_NAME FM_UARTSW_MSB_N
J 0
(-4585 810);
DISPLAY 0.617021 (-4585 810);
PAINT ORANGE (-4585 810);
WIRE 16 -1 (-4675 750)(-2900 750);
FORCEPROP 2 LAST SIG_NAME FM_UARTSW_LSB_N
J 0
(-4585 760);
DISPLAY 0.617021 (-4585 760);
PAINT ORANGE (-4585 760);
WIRE 16 -1 (-750 3450)(-1800 3450);
WIRE 16 -1 (-750 2625)(-650 2625);
WIRE 16 -1 (-750 2625)(-750 3450);
WIRE 16 -1 (-1225 2625)(-750 2625);
FORCEPROP 2 LAST SIG_NAME SPA_MID_DBG_TX
J 0
(-1185 2635);
DISPLAY 0.617021 (-1185 2635);
PAINT ORANGE (-1185 2635);
WIRE 16 -1 (-50 4675)(-50 4350);
WIRE 16 -1 (-50 4675)(-50 4875);
WIRE 16 -1 (-1925 4350)(-50 4350);
WIRE 16 -1 (-4525 4350)(-3850 4350);
WIRE 16 -1 (-3850 4350)(-3225 4350);
WIRE 16 -1 (-1925 4875)(-1925 4350);
WIRE 16 -1 (-50 4875)(-1925 4875);
WIRE 16 -1 (-1925 4350)(-2625 4350);
WIRE 16 -1 (-2625 4350)(-3225 4350);
WIRE 16 -1 (-3850 4775)(-3850 4350);
WIRE 16 -1 (-4525 4350)(-4525 4675);
WIRE 16 -1 (-50 4675)(-4525 4675);
WIRE 16 -1 (-4525 4775)(-4525 4675);
WIRE 16 -1 (-4525 4775)(-3850 4775);
WIRE 16 -1 (-2625 4350)(-2625 4875);
WIRE 16 -1 (-2625 4875)(-1925 4875);
WIRE 16 -1 (-3850 4775)(-3225 4775);
WIRE 16 -1 (-3225 4775)(-3225 4350);
WIRE 16 -1 (-3225 4875)(-3225 4775);
WIRE 16 -1 (-3225 4875)(-2625 4875);
WIRE 16 -1 (-4525 4875)(-4525 4775);
WIRE 16 -1 (-4525 4875)(-3225 4875);
WIRE 16 -1 (-3025 3750)(-2975 3750);
WIRE 16 -1 (-2425 2575)(-2975 2575);
WIRE 16 -1 (-2975 2575)(-2975 3750);
WIRE 16 -1 (-3050 2575)(-2975 2575);
FORCEPROP 2 LAST SIG_NAME SP2_BMC_CM_UART_TX_R
J 0
(-3010 2585);
DISPLAY 0.617021 (-3010 2585);
PAINT ORANGE (-3010 2585);
FORCEPROP 2 LASTPROP $XRERR UNIQUE?
J 0
(-3250 2585);
DISPLAY 0.638298 (-3250 2585);
PAINT MONO (-3250 2585);
DISPLAY INVISIBLE (-3250 2585);
WIRE 16 -1 (-1925 2475)(-1850 2475);
WIRE 16 -1 (-1850 2475)(-1850 2025);
WIRE 16 -1 (-3450 2025)(-1850 2025);
FORCEPROP 2 LAST SIG_NAME FM_UARTSW_LSB_N
J 0
(-3360 2035);
DISPLAY 0.617021 (-3360 2035);
PAINT ORANGE (-3360 2035);
WIRE 16 -1 (-1925 2625)(-1425 2625);
FORCEPROP 2 LAST SIG_NAME UART_MUX_OUT_R
J 2
(-1475 2635);
DISPLAY 0.617021 (-1475 2635);
PAINT ORANGE (-1475 2635);
FORCEPROP 2 LASTPROP $XRERR UNIQUE?
J 0
(-1715 2635);
DISPLAY 0.638298 (-1715 2635);
PAINT MONO (-1715 2635);
DISPLAY INVISIBLE (-1715 2635);
WIRE 16 -1 (-1925 2525)(-1800 2525);
WIRE 16 -1 (-1800 2525)(-1800 1975);
WIRE 16 -1 (-3450 1975)(-1800 1975);
FORCEPROP 2 LAST SIG_NAME FM_UARTSW_MSB_N
J 0
(-3360 1985);
DISPLAY 0.617021 (-3360 1985);
PAINT ORANGE (-3360 1985);
WIRE 2 273 (-4325 4150)(-4325 2175);
WIRE 2 273 (-2750 4150)(-4325 4150);
WIRE 2 273 (-4325 2175)(-2750 2175);
WIRE 2 273 (-2750 2175)(-2750 4150);
WIRE 16 -1 (-3275 2575)(-3900 2575);
FORCEPROP 2 LAST SIG_NAME SP2_BMC_CM_UART_TX
J 0
(-3810 2585);
DISPLAY 0.617021 (-3810 2585);
PAINT ORANGE (-3810 2585);
WIRE 16 -1 (-3250 2575)(-3275 2575);
WIRE 16 -1 (-3275 3450)(-3275 2575);
WIRE 16 -1 (-3275 3450)(-2000 3450);
WIRE 16 -1 (-3900 2625)(-2425 2625);
FORCEPROP 2 LAST SIG_NAME UART_BMC_TXD5
J 0
(-3810 2635);
DISPLAY 0.617021 (-3810 2635);
PAINT ORANGE (-3810 2635);
WIRE 16 -1 (-4025 1525)(-2750 1525);
WIRE 16 -1 (-4025 900)(-3725 900);
WIRE 16 -1 (-4025 900)(-4025 1525);
WIRE 16 -1 (-4675 900)(-4025 900);
FORCEPROP 2 LAST SIG_NAME SPA_MID_DBG_RX
J 0
(-4585 910);
DISPLAY 0.680851 (-4585 910);
PAINT ORANGE (-4585 910);
WIRE 16 -1 (-4975 3200)(-5625 3200);
FORCEPROP 2 LAST SIG_NAME FM_UARTSW_LSB_R_N
J 0
(-5510 3210);
DISPLAY 0.617021 (-5510 3210);
PAINT ORANGE (-5510 3210);
FORCEPROP 2 LASTPROP $XRERR UNIQUE?
J 0
(-5750 3210);
DISPLAY 0.638298 (-5750 3210);
PAINT MONO (-5750 3210);
DISPLAY INVISIBLE (-5750 3210);
WIRE 16 -1 (-3900 2675)(-2425 2675);
FORCEPROP 2 LAST SIG_NAME SP1_BMC_HOST_UART_TX
J 0
(-3810 2685);
DISPLAY 0.617021 (-3810 2685);
PAINT ORANGE (-3810 2685);
WIRE 16 -1 (-7050 3600)(-5825 3600);
FORCEPROP 2 LAST SIG_NAME FM_UARTSW_MSB_N
J 0
(-7010 3610);
DISPLAY 0.617021 (-7010 3610);
PAINT ORANGE (-7010 3610);
WIRE 16 -1 (-4975 3600)(-5625 3600);
FORCEPROP 2 LAST SIG_NAME FM_UARTSW_MSB_R_N
J 0
(-5510 3610);
DISPLAY 0.617021 (-5510 3610);
PAINT ORANGE (-5510 3610);
FORCEPROP 2 LASTPROP $XRERR UNIQUE?
J 0
(-5750 3610);
DISPLAY 0.638298 (-5750 3610);
PAINT MONO (-5750 3610);
DISPLAY INVISIBLE (-5750 3610);
WIRE 16 -1 (-3875 3750)(-3225 3750);
FORCEPROP 2 LAST SIG_NAME SP2_BMC_CM_UART_TX_R1
J 0
(-3835 3760);
DISPLAY 0.617021 (-3835 3760);
PAINT ORANGE (-3835 3760);
WIRE 16 -1 (-7050 3200)(-5825 3200);
FORCEPROP 2 LAST SIG_NAME FM_UARTSW_LSB_N
J 0
(-7010 3210);
DISPLAY 0.617021 (-7010 3210);
PAINT ORANGE (-7010 3210);
DOT 1 (-2300 950);
DOT 1 (-2025 1400);
DOT 1 (-2300 1400);
DOT 1 (-1750 850);
DOT 1 (-2025 900);
DOT 1 (-1375 850);
DOT 1 (-1075 850);
DOT 1 (-3275 2575);
DOT 1 (-3100 1350);
DOT 1 (-4525 4775);
DOT 1 (-4025 900);
DOT 1 (-50 4675);
DOT 1 (-1925 4875);
DOT 1 (-2625 4875);
DOT 1 (-2625 4350);
DOT 1 (-3225 4875);
DOT 1 (-3850 4775);
DOT 1 (-3850 4350);
DOT 1 (-2975 2575);
DOT 1 (-4525 4675);
DOT 1 (-4400 3600);
DOT 1 (-3225 4775);
DOT 1 (-3225 4350);
DOT 1 (-1925 4350);
DOT 1 (-1850 3075);
DOT 1 (-750 2625);
FORCENOTE
NOPOP R9F66 1123
(-3925 3000) 0;
DISPLAY LEFT (-3925 3000);
DISPLAY 1.021277 (-3925 3000);
PAINT RED (-3925 3000);
FORCENOTE
FROM MIDPLANE CONN A
(-4300 3650) 0;
DISPLAY LEFT (-4300 3650);
DISPLAY 1.021277 (-4300 3650);
PAINT PURPLE (-4300 3650);
FORCENOTE
TP FAB3 ADD RES 1021
(-2425 750) 0;
DISPLAY LEFT (-2425 750);
DISPLAY 0.638298 (-2425 750);
PAINT RED (-2425 750);
FORCENOTE
TO MIDPLANE CONN A
(-1100 1625) 0;
DISPLAY LEFT (-1100 1625);
DISPLAY 1.021277 (-1100 1625);
PAINT PURPLE (-1100 1625);
FORCENOTE
NOPOP R9F68 1123
(-750 525) 0;
DISPLAY LEFT (-750 525);
DISPLAY 1.021277 (-750 525);
PAINT RED (-750 525);
FORCENOTE
TP FAB1 POP R9F69
(-975 575) 0;
DISPLAY LEFT (-975 575);
DISPLAY 1.021277 (-975 575);
PAINT RED (-975 575);
FORCENOTE
UART5: DEBUG UART (IE/BMC)
(-1875 4525) 0;
DISPLAY LEFT (-1875 4525);
DISPLAY 1.021277 (-1875 4525);
PAINT PURPLE (-1875 4525);
FORCENOTE
UART2: IPMI OVER SERIAL (IE/BMC)
(-1875 4450) 0;
DISPLAY LEFT (-1875 4450);
DISPLAY 1.021277 (-1875 4450);
PAINT PURPLE (-1875 4450);
FORCENOTE
NO CONNECTION
(-1875 4375) 0;
DISPLAY LEFT (-1875 4375);
DISPLAY 1.021277 (-1875 4375);
PAINT PURPLE (-1875 4375);
FORCENOTE
MSB GREEN
(-3100 4800) 0;
DISPLAY LEFT (-3100 4800);
DISPLAY 1.021277 (-3100 4800);
PAINT PURPLE (-3100 4800);
FORCENOTE
FM_UARTSW_MSB_N
(-3150 4700) 0;
DISPLAY LEFT (-3150 4700);
DISPLAY 0.808511 (-3150 4700);
PAINT PURPLE (-3150 4700);
FORCENOTE
TP FAB1 POP R9F65
(-4175 3075) 0;
DISPLAY LEFT (-4175 3075);
DISPLAY 1.021277 (-4175 3075);
PAINT RED (-4175 3075);
FORCENOTE
1
(-4250 4525) 0;
DISPLAY LEFT (-4250 4525);
DISPLAY 1.021277 (-4250 4525);
PAINT PURPLE (-4250 4525);
FORCENOTE
0
(-4250 4450) 0;
DISPLAY LEFT (-4250 4450);
DISPLAY 1.021277 (-4250 4450);
PAINT PURPLE (-4250 4450);
FORCENOTE
FM_UARTSW_MSB_N
(-4450 4700) 0;
DISPLAY LEFT (-4450 4700);
DISPLAY 0.808511 (-4450 4700);
PAINT PURPLE (-4450 4700);
FORCENOTE
ON
(-2950 4450) 0;
DISPLAY LEFT (-2950 4450);
DISPLAY 1.021277 (-2950 4450);
PAINT PURPLE (-2950 4450);
FORCENOTE
CPLD MAPPING
(-4100 4800) 0;
DISPLAY LEFT (-4100 4800);
DISPLAY 1.021277 (-4100 4800);
PAINT PURPLE (-4100 4800);
FORCENOTE
FM_UARTSW_LSB_N
(-3800 4700) 0;
DISPLAY LEFT (-3800 4700);
DISPLAY 0.808511 (-3800 4700);
PAINT PURPLE (-3800 4700);
FORCENOTE
1
(-3600 4600) 0;
DISPLAY LEFT (-3600 4600);
DISPLAY 1.021277 (-3600 4600);
PAINT PURPLE (-3600 4600);
FORCENOTE
ON
(-2950 4375) 0;
DISPLAY LEFT (-2950 4375);
DISPLAY 1.021277 (-2950 4375);
PAINT PURPLE (-2950 4375);
FORCENOTE
LSB GREEN
(-2425 4800) 0;
DISPLAY LEFT (-2425 4800);
DISPLAY 1.021277 (-2425 4800);
PAINT PURPLE (-2425 4800);
FORCENOTE
FM_UARTSW_LSB_N
(-2500 4700) 0;
DISPLAY LEFT (-2500 4700);
DISPLAY 0.808511 (-2500 4700);
PAINT PURPLE (-2500 4700);
FORCENOTE
OFF
(-2300 4600) 0;
DISPLAY LEFT (-2300 4600);
DISPLAY 1.021277 (-2300 4600);
PAINT PURPLE (-2300 4600);
FORCENOTE
ON
(-2300 4525) 0;
DISPLAY LEFT (-2300 4525);
DISPLAY 1.021277 (-2300 4525);
PAINT PURPLE (-2300 4525);
FORCENOTE
OFF
(-2300 4450) 0;
DISPLAY LEFT (-2300 4450);
DISPLAY 1.021277 (-2300 4450);
PAINT PURPLE (-2300 4450);
FORCENOTE
OFF
(-2950 4600) 0;
DISPLAY LEFT (-2950 4600);
DISPLAY 1.021277 (-2950 4600);
PAINT PURPLE (-2950 4600);
FORCENOTE
OFF
(-2950 4525) 0;
DISPLAY LEFT (-2950 4525);
DISPLAY 1.021277 (-2950 4525);
PAINT PURPLE (-2950 4525);
FORCENOTE
0
(-3600 4375) 0;
DISPLAY LEFT (-3600 4375);
DISPLAY 1.021277 (-3600 4375);
PAINT PURPLE (-3600 4375);
FORCENOTE
1
(-3600 4450) 0;
DISPLAY LEFT (-3600 4450);
DISPLAY 1.021277 (-3600 4450);
PAINT PURPLE (-3600 4450);
FORCENOTE
0
(-3600 4525) 0;
DISPLAY LEFT (-3600 4525);
DISPLAY 1.021277 (-3600 4525);
PAINT PURPLE (-3600 4525);
FORCENOTE
1
(-4250 4600) 0;
DISPLAY LEFT (-4250 4600);
DISPLAY 1.021277 (-4250 4600);
PAINT PURPLE (-4250 4600);
FORCENOTE
0
(-4250 4375) 0;
DISPLAY LEFT (-4250 4375);
DISPLAY 1.021277 (-4250 4375);
PAINT PURPLE (-4250 4375);
FORCENOTE
ROOM=UART_MUX
(-7750 325) 0;
DISPLAY LEFT (-7750 325);
DISPLAY 1.595745 (-7750 325);
PAINT PURPLE (-7750 325);
FORCENOTE
BOM_COST=DEBUG
(-7750 200) 0;
DISPLAY LEFT (-7750 200);
DISPLAY 1.595745 (-7750 200);
PAINT PURPLE (-7750 200);
FORCENOTE
ON
(-2300 4375) 0;
DISPLAY LEFT (-2300 4375);
DISPLAY 1.021277 (-2300 4375);
PAINT PURPLE (-2300 4375);
FORCENOTE
UART1: HOST UART/EMS (IE/BMC)
(-1875 4600) 0;
DISPLAY LEFT (-1875 4600);
DISPLAY 1.021277 (-1875 4600);
PAINT PURPLE (-1875 4600);
FORCENOTE
MIDPLANE/DEBUG CONNECTOR CONNECTED TO
(-1875 4700) 0;
DISPLAY LEFT (-1875 4700);
DISPLAY 1.021277 (-1875 4700);
PAINT PURPLE (-1875 4700);
FORCENOTE
$CDS_IMAGE|123.bmp|3500|1795
(-6125 1950) 0;
DISPLAY LEFT (-6125 1950);
QUIT
